G04 ================== begin FILE IDENTIFICATION RECORD ==================*
G04 Layout Name:  9054_F0T_PDB_BD_GPU_F_V04_1213_1550.brd*
G04 Film Name:    ssb*
G04 File Format:  Gerber RS274X*
G04 File Origin:  Cadence Allegro 17.2-S081*
G04 Origin Date:  Wed Dec 28 10:19:03 2022*
G04 *
G04 Layer:  DRAWING FORMAT/TITLE_BLOCK_A*
G04 Layer:  BOARD GEOMETRY/DESIGN_OUTLINE*
G04 Layer:  BOARD GEOMETRY/CUTOUT*
G04 Layer:  BOARD GEOMETRY/OUTLINE*
G04 Layer:  DRAWING FORMAT/TITLE_BLOCK*
G04 Layer:  MANUFACTURING/TP_TEXT_BOTTOM*
G04 Layer:  REF DES/SILKSCREEN_BOTTOM*
G04 Layer:  PACKAGE GEOMETRY/SILKSCREEN_BOTTOM*
G04 Layer:  MANUFACTURING/PHOTOPLOT_OUTLINE*
G04 Layer:  DRAWING FORMAT/TITLE_DATA_SSB*
G04 Layer:  BOARD GEOMETRY/SILKSCREEN_BOTTOM*
G04 *
G04 Offset:    (0.00 0.00)*
G04 Mirror:    No*
G04 Mode:      Positive*
G04 Rotation:  0*
G04 FullContactRelief:  No*
G04 UndefLineWidth:     6.00*
G04 ================== end FILE IDENTIFICATION RECORD ====================*
%FSLAX25Y25*MOIN*%
%IR0*IPPOS*OFA0.00000B0.00000*MIA0B0*SFA1.00000B1.00000*%
%ADD10C,.006*%
G75*
%LPD*%
G75*
G36*
G01X609984Y241161D02*
Y237161D01*
X613984Y239161D01*
X609984Y241161D01*
G37*
G36*
G01X590408Y264024D02*
X592708D01*
Y261724D01*
X590408D01*
Y264024D01*
G37*
G36*
G01X680156Y261068D02*
X677328Y263897D01*
X681571Y265311D01*
X680156Y261068D01*
G37*
G36*
G01X1082837Y290718D02*
X1085666Y287890D01*
X1081423Y286476D01*
X1082837Y290718D01*
G37*
G36*
G01X1119500Y353500D02*
X1117500D01*
X1118500Y355500D01*
X1119500Y353500D01*
G37*
G36*
G01X1152300Y310839D02*
Y314839D01*
X1148300Y312839D01*
X1152300Y310839D01*
G37*
G36*
G01X1147738Y337941D02*
X1143738Y335941D01*
Y339941D01*
X1147738Y337941D01*
G37*
G36*
G01X1171876Y287976D02*
X1169576D01*
Y290276D01*
X1171876D01*
Y287976D01*
G37*
G36*
G01X1170941Y371262D02*
X1168941Y375262D01*
X1172941D01*
X1170941Y371262D01*
G37*
G36*
G01X1639700Y145264D02*
X1636700Y146764D01*
Y143764D01*
X1639700Y145264D01*
G37*
G36*
G01X1744500Y182760D02*
Y184760D01*
X1746500Y183760D01*
X1744500Y182760D01*
G37*
G54D10*
G01X-457143Y-1211429D02*
Y2242857D01*
X4308572D01*
Y-1211429D01*
X-457143D01*
G01X1874016Y85709D02*
Y499094D01*
G03X1854331Y518780I-19686J0D01*
G01X1751969D01*
G02X1732283Y538465I0J19686D01*
G01Y603543D01*
G03X1712598Y623228I-19685J0D01*
G01X1629921D01*
G02X1610236Y642913I0J19685D01*
G01Y656102D01*
G03X1590551Y675787I-19685J0D01*
G01X1437008D01*
G03X1417323Y656102I0J-19685D01*
G01Y635039D01*
G02X1405512Y623228I-11811J0D01*
G01X1403543D01*
G03X1383858Y603543I0J-19685D01*
G01Y435039D01*
G02X1354331Y405512I-29527J0D01*
G01X377953D01*
G02X348425Y435039I-1J29527D01*
G01Y603543D01*
G03X328740Y623228I-19685J0D01*
G01X326772D01*
G02X314961Y635039I0J11811D01*
G01Y656102D01*
G03X295276Y675787I-19685J0D01*
G01X141732D01*
G03X122047Y656102I0J-19685D01*
G01Y642913D01*
G02X102362Y623228I-19685J0D01*
G01X19685D01*
G03X0Y603543I0J-19685D01*
G01Y19685D01*
G03X19685Y0I19685J0D01*
G01X1712598D01*
G03X1732283Y19685I0J19685D01*
G01Y46339D01*
G02X1751969Y66024I19685J0D01*
G01X1854331D01*
G03X1874016Y85709I0J19685D01*
G01X37000Y-995000D02*
Y-1070000D01*
X537000D01*
Y-995000D01*
X37000D01*
G01X41339Y17717D02*
Y23763D01*
G03X38916Y32156I-15749J0D01*
G02X55572I8328J5245D01*
G03X53150Y23763I13326J-8392D01*
G01Y17717D01*
G02X41339I-5905J0D01*
G01Y23763D02*
G03X38916Y32156I-15749J0D01*
G02X55572I8328J5245D01*
G03X53150Y23763I13326J-8392D01*
G01Y17717D01*
G02X41339I-5905J0D01*
G01Y23763D01*
G01Y330709D02*
Y336756D01*
G03X38916Y345148I-15747J-1D01*
G02X55572I8328J5245D01*
G03X53150Y336756I13324J-8391D01*
G01Y330709D01*
G02X41339I-5905J0D01*
G01Y336756D02*
G03X38916Y345148I-15747J-1D01*
G02X55572I8328J5245D01*
G03X53150Y336756I13324J-8391D01*
G01Y330709D01*
G02X41339I-5905J0D01*
G01Y336756D01*
G01X19685Y541339D02*
G02X44882I12598J0D01*
G02X19685I-12599J0D01*
G01D02*
G02X44882I12598J0D01*
G02X19685I-12599J0D01*
G01X49000Y-1060000D02*
Y-1065000D01*
G01X47543Y-1060000D02*
X50457D01*
G01X55367Y-1065000D02*
X52833D01*
Y-1060000D01*
X55367D01*
G01X54353Y-1062417D02*
X52833D01*
G01X57933Y-1060000D02*
Y-1065000D01*
X60467D01*
G01X64300Y-1065167D02*
X64173Y-1065083D01*
Y-1064917D01*
X64300Y-1064833D01*
X64427Y-1064917D01*
Y-1065083D01*
X64300Y-1065167D01*
G01Y-1062917D02*
X64173Y-1062833D01*
Y-1062667D01*
X64300Y-1062583D01*
X64427Y-1062667D01*
Y-1062833D01*
X64300Y-1062917D01*
G01X69083Y-1066667D02*
X68450Y-1065833D01*
X68133Y-1065000D01*
Y-1061667D01*
X68450Y-1060833D01*
X69083Y-1060000D01*
G01X74500D02*
X73993Y-1060167D01*
X73613Y-1060583D01*
X73360Y-1061083D01*
X73170Y-1061750D01*
X73107Y-1062500D01*
X73170Y-1063250D01*
X73360Y-1063917D01*
X73613Y-1064417D01*
X73993Y-1064833D01*
X74500Y-1065000D01*
X75007Y-1064833D01*
X75387Y-1064417D01*
X75640Y-1063917D01*
X75830Y-1063250D01*
X75893Y-1062500D01*
X75830Y-1061750D01*
X75640Y-1061083D01*
X75387Y-1060583D01*
X75007Y-1060167D01*
X74500Y-1060000D01*
G01X78207Y-1064000D02*
X78587Y-1064583D01*
X79093Y-1064917D01*
X79663Y-1065000D01*
X80170Y-1064917D01*
X80677Y-1064500D01*
X80993Y-1064000D01*
X81057Y-1063500D01*
X80930Y-1062917D01*
X80487Y-1062500D01*
X80043Y-1062333D01*
X79473D01*
G01X80043D02*
X80423Y-1062083D01*
X80740Y-1061667D01*
X80867Y-1061167D01*
X80740Y-1060667D01*
X80423Y-1060250D01*
X79853Y-1060000D01*
X79283Y-1060083D01*
X78713Y-1060417D01*
G01X85017Y-1066667D02*
X85650Y-1065833D01*
X85967Y-1065000D01*
Y-1061667D01*
X85650Y-1060833D01*
X85017Y-1060000D01*
G01X88407Y-1064000D02*
X88787Y-1064583D01*
X89293Y-1064917D01*
X89863Y-1065000D01*
X90370Y-1064917D01*
X90877Y-1064500D01*
X91193Y-1064000D01*
X91257Y-1063500D01*
X91130Y-1062917D01*
X90687Y-1062500D01*
X90243Y-1062333D01*
X89673D01*
G01X90243D02*
X90623Y-1062083D01*
X90940Y-1061667D01*
X91067Y-1061167D01*
X90940Y-1060667D01*
X90623Y-1060250D01*
X90053Y-1060000D01*
X89483Y-1060083D01*
X88913Y-1060417D01*
G01X93697Y-1060833D02*
X94077Y-1060333D01*
X94520Y-1060083D01*
X95027Y-1060000D01*
X95660Y-1060167D01*
X96103Y-1060583D01*
X96230Y-1061083D01*
X96167Y-1061583D01*
X95913Y-1062000D01*
X94647Y-1062833D01*
X94077Y-1063417D01*
X93697Y-1064250D01*
X93570Y-1065000D01*
X96230D01*
G01X99873D02*
X100000Y-1063917D01*
X100190Y-1063000D01*
X100443Y-1062167D01*
X100760Y-1061250D01*
X101267Y-1060000D01*
X98733D01*
G01X104277Y-1063333D02*
X105923D01*
G01X108997Y-1060833D02*
X109377Y-1060333D01*
X109820Y-1060083D01*
X110327Y-1060000D01*
X110960Y-1060167D01*
X111403Y-1060583D01*
X111530Y-1061083D01*
X111467Y-1061583D01*
X111213Y-1062000D01*
X109947Y-1062833D01*
X109377Y-1063417D01*
X108997Y-1064250D01*
X108870Y-1065000D01*
X111530D01*
G01X113907Y-1064000D02*
X114287Y-1064583D01*
X114793Y-1064917D01*
X115363Y-1065000D01*
X115870Y-1064917D01*
X116377Y-1064500D01*
X116693Y-1064000D01*
X116757Y-1063500D01*
X116630Y-1062917D01*
X116187Y-1062500D01*
X115743Y-1062333D01*
X115173D01*
G01X115743D02*
X116123Y-1062083D01*
X116440Y-1061667D01*
X116567Y-1061167D01*
X116440Y-1060667D01*
X116123Y-1060250D01*
X115553Y-1060000D01*
X114983Y-1060083D01*
X114413Y-1060417D01*
G01X121160Y-1065000D02*
Y-1060000D01*
X118817Y-1063583D01*
X121983D01*
G01X124107Y-1064250D02*
X124487Y-1064667D01*
X124930Y-1064917D01*
X125500Y-1065000D01*
X126070Y-1064833D01*
X126513Y-1064500D01*
X126830Y-1063917D01*
X126893Y-1063250D01*
X126767Y-1062583D01*
X126450Y-1062167D01*
X126007Y-1061833D01*
X125563Y-1061750D01*
X125120Y-1061833D01*
X124550Y-1062167D01*
X124740Y-1060000D01*
X126450D01*
G01X134497Y-1065000D02*
Y-1060000D01*
X136903D01*
G01X136017Y-1062417D02*
X134497D01*
G01X139217Y-1065000D02*
X140800Y-1060000D01*
X142383Y-1065000D01*
G01X141813Y-1063250D02*
X139787D01*
G01X144570Y-1065000D02*
X147230Y-1060000D01*
G01X144570D02*
X147230Y-1065000D01*
G01X151000Y-1065167D02*
X150873Y-1065083D01*
Y-1064917D01*
X151000Y-1064833D01*
X151127Y-1064917D01*
Y-1065083D01*
X151000Y-1065167D01*
G01Y-1062917D02*
X150873Y-1062833D01*
Y-1062667D01*
X151000Y-1062583D01*
X151127Y-1062667D01*
Y-1062833D01*
X151000Y-1062917D01*
G01X155783Y-1066667D02*
X155150Y-1065833D01*
X154833Y-1065000D01*
Y-1061667D01*
X155150Y-1060833D01*
X155783Y-1060000D01*
G01X161200D02*
X160693Y-1060167D01*
X160313Y-1060583D01*
X160060Y-1061083D01*
X159870Y-1061750D01*
X159807Y-1062500D01*
X159870Y-1063250D01*
X160060Y-1063917D01*
X160313Y-1064417D01*
X160693Y-1064833D01*
X161200Y-1065000D01*
X161707Y-1064833D01*
X162087Y-1064417D01*
X162340Y-1063917D01*
X162530Y-1063250D01*
X162593Y-1062500D01*
X162530Y-1061750D01*
X162340Y-1061083D01*
X162087Y-1060583D01*
X161707Y-1060167D01*
X161200Y-1060000D01*
G01X164907Y-1064000D02*
X165287Y-1064583D01*
X165793Y-1064917D01*
X166363Y-1065000D01*
X166870Y-1064917D01*
X167377Y-1064500D01*
X167693Y-1064000D01*
X167757Y-1063500D01*
X167630Y-1062917D01*
X167187Y-1062500D01*
X166743Y-1062333D01*
X166173D01*
G01X166743D02*
X167123Y-1062083D01*
X167440Y-1061667D01*
X167567Y-1061167D01*
X167440Y-1060667D01*
X167123Y-1060250D01*
X166553Y-1060000D01*
X165983Y-1060083D01*
X165413Y-1060417D01*
G01X171717Y-1066667D02*
X172350Y-1065833D01*
X172667Y-1065000D01*
Y-1061667D01*
X172350Y-1060833D01*
X171717Y-1060000D01*
G01X175107Y-1064000D02*
X175487Y-1064583D01*
X175993Y-1064917D01*
X176563Y-1065000D01*
X177070Y-1064917D01*
X177577Y-1064500D01*
X177893Y-1064000D01*
X177957Y-1063500D01*
X177830Y-1062917D01*
X177387Y-1062500D01*
X176943Y-1062333D01*
X176373D01*
G01X176943D02*
X177323Y-1062083D01*
X177640Y-1061667D01*
X177767Y-1061167D01*
X177640Y-1060667D01*
X177323Y-1060250D01*
X176753Y-1060000D01*
X176183Y-1060083D01*
X175613Y-1060417D01*
G01X180523Y-1064417D02*
X180967Y-1064833D01*
X181473Y-1065000D01*
X181980Y-1064833D01*
X182423Y-1064333D01*
X182740Y-1063583D01*
X182867Y-1062833D01*
Y-1061917D01*
X182740Y-1061167D01*
X182423Y-1060500D01*
X182043Y-1060167D01*
X181600Y-1060000D01*
X181093Y-1060167D01*
X180713Y-1060500D01*
X180460Y-1061000D01*
X180333Y-1061667D01*
X180460Y-1062250D01*
X180777Y-1062833D01*
X181157Y-1063167D01*
X181600Y-1063250D01*
X182107Y-1063083D01*
X182487Y-1062667D01*
X182867Y-1061917D01*
G01X186573Y-1065000D02*
X186700Y-1063917D01*
X186890Y-1063000D01*
X187143Y-1062167D01*
X187460Y-1061250D01*
X187967Y-1060000D01*
X185433D01*
G01X190977Y-1063333D02*
X192623D01*
G01X195507Y-1064000D02*
X195887Y-1064583D01*
X196393Y-1064917D01*
X196963Y-1065000D01*
X197470Y-1064917D01*
X197977Y-1064500D01*
X198293Y-1064000D01*
X198357Y-1063500D01*
X198230Y-1062917D01*
X197787Y-1062500D01*
X197343Y-1062333D01*
X196773D01*
G01X197343D02*
X197723Y-1062083D01*
X198040Y-1061667D01*
X198167Y-1061167D01*
X198040Y-1060667D01*
X197723Y-1060250D01*
X197153Y-1060000D01*
X196583Y-1060083D01*
X196013Y-1060417D01*
G01X200797Y-1062917D02*
X201240Y-1062333D01*
X201620Y-1062000D01*
X202127Y-1061833D01*
X202570Y-1062000D01*
X202887Y-1062333D01*
X203140Y-1062833D01*
X203203Y-1063417D01*
X203140Y-1063917D01*
X202887Y-1064417D01*
X202507Y-1064833D01*
X202063Y-1065000D01*
X201557Y-1064833D01*
X201113Y-1064333D01*
X200860Y-1063583D01*
X200797Y-1062750D01*
X200923Y-1061667D01*
X201113Y-1061083D01*
X201430Y-1060500D01*
X201873Y-1060083D01*
X202317Y-1060000D01*
X202760Y-1060167D01*
X203077Y-1060583D01*
G01X207100Y-1065000D02*
Y-1060000D01*
X206340Y-1061000D01*
G01Y-1065000D02*
X207860D01*
G01X212960D02*
Y-1060000D01*
X210617Y-1063583D01*
X213783D01*
G01X51181Y236614D02*
G02X66929I7874J0D01*
G02X51181I-7874J0D01*
G01D02*
G02X66929I7874J0D01*
G02X51181I-7874J0D01*
G01Y411614D02*
G02X66929I7874J0D01*
G02X51181I-7874J0D01*
G01D02*
G02X66929I7874J0D01*
G02X51181I-7874J0D01*
G01X46457Y498031D02*
G02X71654I12598J0D01*
G02X46457I-12599J0D01*
G01D02*
G02X71654I12598J0D01*
G02X46457I-12599J0D01*
G01X203691Y639094D02*
G02X212057I4183J0D01*
G02X203691I-4183J0D01*
G01D02*
G02X212057I4183J0D01*
G02X203691I-4183J0D01*
G01X232000Y-995000D02*
Y-1070000D01*
G01Y-1045000D02*
X335000D01*
Y-1020000D01*
G01X232000D02*
X335000D01*
G01X236142Y15512D02*
G02X245591I4724J0D01*
G02X236142I-4724J0D01*
G01D02*
G02X245591I4724J0D01*
G02X236142I-4724J0D01*
G01X273622Y53150D02*
Y59196D01*
G03X271199Y67589I-15749J0D01*
G02X287856I8329J5246D01*
G03X285433Y59196I13326J-8393D01*
G01Y53150D01*
G02X273622I-5905J0D01*
G01Y59196D02*
G03X271199Y67589I-15749J0D01*
G02X287856I8329J5246D01*
G03X285433Y59196I13326J-8393D01*
G01Y53150D01*
G02X273622I-5905J0D01*
G01Y59196D01*
G01X283268Y628465D02*
G02X291535I4134J0D01*
G02X283268I-4134J0D01*
G01D02*
G02X291535I4134J0D01*
G02X283268I-4134J0D01*
G01X259646Y659961D02*
G02X267913I4134J0D01*
G02X259646I-4134J0D01*
G01D02*
G02X267913I4134J0D01*
G02X259646I-4134J0D01*
G01X296142Y10197D02*
G02X305591I4725J0D01*
G02X296142I-4724J0D01*
G01D02*
G02X305591I4725J0D01*
G02X296142I-4724J0D01*
G01X320866Y561024D02*
G02X309055I-5905J0D01*
G01Y567070D01*
G03X306632Y575463I-15749J0D01*
G02X323289I8329J5246D01*
G03X320866Y567070I13326J-8393D01*
G01Y561024D01*
G01X309055D02*
Y567070D01*
G03X306632Y575463I-15749J0D01*
G02X323289I8329J5246D01*
G03X320866Y567070I13326J-8393D01*
G01Y561024D01*
G02X309055I-5905J0D01*
G01X337000Y-995000D02*
Y-1070000D01*
G01X335000Y-995000D02*
Y-1070000D01*
G01X342507Y-1055000D02*
Y-1050000D01*
X343773D01*
X344280Y-1050250D01*
X344660Y-1050583D01*
X344977Y-1051083D01*
X345230Y-1051667D01*
X345293Y-1052500D01*
X345230Y-1053333D01*
X344977Y-1053917D01*
X344660Y-1054417D01*
X344280Y-1054750D01*
X343773Y-1055000D01*
X342507D01*
G01X347417D02*
X349000Y-1050000D01*
X350583Y-1055000D01*
G01X350013Y-1053250D02*
X347987D01*
G01X354100Y-1050000D02*
Y-1055000D01*
G01X352643Y-1050000D02*
X355557D01*
G01X360467Y-1055000D02*
X357933D01*
Y-1050000D01*
X360467D01*
G01X359453Y-1052417D02*
X357933D01*
G01X364300Y-1055167D02*
X364173Y-1055083D01*
Y-1054917D01*
X364300Y-1054833D01*
X364427Y-1054917D01*
Y-1055083D01*
X364300Y-1055167D01*
G01Y-1052917D02*
X364173Y-1052833D01*
Y-1052667D01*
X364300Y-1052583D01*
X364427Y-1052667D01*
Y-1052833D01*
X364300Y-1052917D01*
G01X337000Y-1045000D02*
X537000D01*
G01X342633Y-1030000D02*
Y-1025000D01*
X344153D01*
X344660Y-1025250D01*
X345040Y-1025833D01*
X345167Y-1026500D01*
X345040Y-1027167D01*
X344723Y-1027667D01*
X344153Y-1027917D01*
X342633D01*
G01X347860Y-1030167D02*
X350140Y-1025000D01*
G01X352643Y-1030000D02*
Y-1025000D01*
X355557Y-1030000D01*
Y-1025000D01*
G01X359200Y-1030167D02*
X359073Y-1030083D01*
Y-1029917D01*
X359200Y-1029833D01*
X359327Y-1029917D01*
Y-1030083D01*
X359200Y-1030167D01*
G01Y-1027917D02*
X359073Y-1027833D01*
Y-1027667D01*
X359200Y-1027583D01*
X359327Y-1027667D01*
Y-1027833D01*
X359200Y-1027917D01*
G01X342633Y-1005000D02*
Y-1000000D01*
X344153D01*
X344660Y-1000250D01*
X345040Y-1000833D01*
X345167Y-1001500D01*
X345040Y-1002167D01*
X344723Y-1002667D01*
X344153Y-1002917D01*
X342633D01*
G01X347733Y-1005000D02*
Y-1000000D01*
X349317D01*
X349823Y-1000250D01*
X350140Y-1000583D01*
X350267Y-1001250D01*
X350140Y-1001917D01*
X349760Y-1002333D01*
X349317Y-1002583D01*
X347733D01*
G01X349317D02*
X350267Y-1005000D01*
G01X354100D02*
X353593Y-1004917D01*
X353150Y-1004583D01*
X352770Y-1004083D01*
X352517Y-1003500D01*
X352390Y-1002833D01*
Y-1002167D01*
X352517Y-1001500D01*
X352770Y-1000917D01*
X353150Y-1000417D01*
X353593Y-1000083D01*
X354100Y-1000000D01*
X354607Y-1000083D01*
X355050Y-1000417D01*
X355430Y-1000917D01*
X355683Y-1001500D01*
X355810Y-1002167D01*
Y-1002833D01*
X355683Y-1003500D01*
X355430Y-1004083D01*
X355050Y-1004583D01*
X354607Y-1004917D01*
X354100Y-1005000D01*
G01X357933Y-1004000D02*
X358250Y-1004500D01*
X358630Y-1004833D01*
X359073Y-1005000D01*
X359580Y-1004833D01*
X359960Y-1004500D01*
X360340Y-1004000D01*
X360467Y-1003333D01*
Y-1000000D01*
G01X365567Y-1005000D02*
X363033D01*
Y-1000000D01*
X365567D01*
G01X364553Y-1002417D02*
X363033D01*
G01X370793Y-1000417D02*
X370413Y-1000167D01*
X369970Y-1000000D01*
X369463D01*
X368893Y-1000250D01*
X368450Y-1000667D01*
X368133Y-1001167D01*
X367880Y-1002000D01*
X367817Y-1002750D01*
X367943Y-1003500D01*
X368133Y-1004000D01*
X368513Y-1004500D01*
X368957Y-1004833D01*
X369400Y-1005000D01*
X369843D01*
X370287Y-1004833D01*
X370667Y-1004583D01*
X370983Y-1004250D01*
G01X374500Y-1000000D02*
Y-1005000D01*
G01X373043Y-1000000D02*
X375957D01*
G01X379600Y-1005167D02*
X379473Y-1005083D01*
Y-1004917D01*
X379600Y-1004833D01*
X379727Y-1004917D01*
Y-1005083D01*
X379600Y-1005167D01*
G01Y-1002917D02*
X379473Y-1002833D01*
Y-1002667D01*
X379600Y-1002583D01*
X379727Y-1002667D01*
Y-1002833D01*
X379600Y-1002917D01*
G01X337000Y-1020000D02*
X537000D01*
G01X387795Y344488D02*
Y350535D01*
G03X385373Y358928I-15748J1D01*
G02X402029I8328J5245D01*
G03X399606Y350535I13326J-8393D01*
G01Y344488D01*
G02X387795I-5905J0D01*
G01Y350535D02*
G03X385373Y358928I-15748J1D01*
G02X402029I8328J5245D01*
G03X399606Y350535I13326J-8393D01*
G01Y344488D01*
G02X387795I-5905J0D01*
G01Y350535D01*
G01X452000Y-1045000D02*
Y-1070000D01*
G01X454633Y-1047500D02*
Y-1052500D01*
X457167D01*
G01X460240Y-1047500D02*
X461760D01*
G01X461000D02*
Y-1052500D01*
G01X460240D02*
X461760D01*
G01X466607Y-1049833D02*
X466860Y-1049583D01*
X467050Y-1049167D01*
X467177Y-1048583D01*
X467050Y-1048083D01*
X466797Y-1047750D01*
X466353Y-1047500D01*
X464643D01*
Y-1052500D01*
X466733D01*
X467177Y-1052167D01*
X467430Y-1051667D01*
X467557Y-1051083D01*
X467430Y-1050500D01*
X467050Y-1050000D01*
X466607Y-1049833D01*
X464643D01*
G01X471200Y-1052667D02*
X471073Y-1052583D01*
Y-1052417D01*
X471200Y-1052333D01*
X471327Y-1052417D01*
Y-1052583D01*
X471200Y-1052667D01*
G01Y-1050417D02*
X471073Y-1050333D01*
Y-1050167D01*
X471200Y-1050083D01*
X471327Y-1050167D01*
Y-1050333D01*
X471200Y-1050417D01*
G01X495000Y-1045000D02*
Y-1070000D01*
G01X498900Y-1047500D02*
Y-1052500D01*
G01X497443Y-1047500D02*
X500357D01*
G01X504000Y-1052500D02*
X503620Y-1052417D01*
X503240Y-1052083D01*
X502987Y-1051500D01*
X502860Y-1050833D01*
X502987Y-1050167D01*
X503240Y-1049583D01*
X503620Y-1049250D01*
X504000Y-1049167D01*
X504380Y-1049250D01*
X504760Y-1049583D01*
X505013Y-1050167D01*
X505077Y-1050833D01*
X505013Y-1051500D01*
X504760Y-1052083D01*
X504380Y-1052417D01*
X504000Y-1052500D01*
G01X509100D02*
X508720Y-1052417D01*
X508340Y-1052083D01*
X508087Y-1051500D01*
X507960Y-1050833D01*
X508087Y-1050167D01*
X508340Y-1049583D01*
X508720Y-1049250D01*
X509100Y-1049167D01*
X509480Y-1049250D01*
X509860Y-1049583D01*
X510113Y-1050167D01*
X510177Y-1050833D01*
X510113Y-1051500D01*
X509860Y-1052083D01*
X509480Y-1052417D01*
X509100Y-1052500D01*
G01X514200D02*
Y-1047500D01*
G01X519300Y-1052667D02*
X519173Y-1052583D01*
Y-1052417D01*
X519300Y-1052333D01*
X519427Y-1052417D01*
Y-1052583D01*
X519300Y-1052667D01*
G01Y-1050417D02*
X519173Y-1050333D01*
Y-1050167D01*
X519300Y-1050083D01*
X519427Y-1050167D01*
Y-1050333D01*
X519300Y-1050417D01*
G01X495000Y-1020000D02*
Y-1045000D01*
G01X497633Y-1027500D02*
Y-1022500D01*
X499217D01*
X499723Y-1022750D01*
X500040Y-1023083D01*
X500167Y-1023750D01*
X500040Y-1024417D01*
X499660Y-1024833D01*
X499217Y-1025083D01*
X497633D01*
G01X499217D02*
X500167Y-1027500D01*
G01X505267D02*
X502733D01*
Y-1022500D01*
X505267D01*
G01X504253Y-1024917D02*
X502733D01*
G01X507517Y-1022500D02*
X509100Y-1027500D01*
X510683Y-1022500D01*
G01X514200Y-1027667D02*
X514073Y-1027583D01*
Y-1027417D01*
X514200Y-1027333D01*
X514327Y-1027417D01*
Y-1027583D01*
X514200Y-1027667D01*
G01Y-1025417D02*
X514073Y-1025333D01*
Y-1025167D01*
X514200Y-1025083D01*
X514327Y-1025167D01*
Y-1025333D01*
X514200Y-1025417D01*
G01X503013Y-1073167D02*
X503120Y-1073042D01*
X503200Y-1072833D01*
X503253Y-1072542D01*
X503200Y-1072292D01*
X503093Y-1072125D01*
X502907Y-1072000D01*
X502187D01*
Y-1074500D01*
X503067D01*
X503253Y-1074333D01*
X503360Y-1074083D01*
X503413Y-1073792D01*
X503360Y-1073500D01*
X503200Y-1073250D01*
X503013Y-1073167D01*
X502187D01*
G01X505480Y-1074500D02*
Y-1072833D01*
G01Y-1073125D02*
X505373Y-1072958D01*
X505213Y-1072875D01*
X505027Y-1072833D01*
X504840Y-1072917D01*
X504680Y-1073083D01*
X504573Y-1073333D01*
X504520Y-1073667D01*
X504573Y-1074000D01*
X504680Y-1074250D01*
X504840Y-1074417D01*
X505027Y-1074500D01*
X505213Y-1074458D01*
X505373Y-1074333D01*
X505480Y-1074167D01*
G01X506800Y-1074208D02*
X506933Y-1074375D01*
X507120Y-1074500D01*
X507280D01*
X507440Y-1074417D01*
X507547Y-1074292D01*
X507600Y-1074125D01*
X507573Y-1073875D01*
X507467Y-1073750D01*
X506987Y-1073500D01*
X506880Y-1073208D01*
X506933Y-1073000D01*
X507040Y-1072875D01*
X507200Y-1072833D01*
X507360Y-1072875D01*
X507520Y-1073000D01*
G01X509000Y-1073375D02*
X509853D01*
X509773Y-1073083D01*
X509640Y-1072917D01*
X509453Y-1072833D01*
X509267Y-1072875D01*
X509107Y-1073000D01*
X509000Y-1073292D01*
X508947Y-1073542D01*
Y-1073792D01*
X509000Y-1074042D01*
X509133Y-1074292D01*
X509293Y-1074458D01*
X509480Y-1074500D01*
X509667Y-1074417D01*
X509853Y-1074167D01*
G01X511120Y-1074500D02*
Y-1072000D01*
G01Y-1073250D02*
X511253Y-1073000D01*
X511413Y-1072875D01*
X511573Y-1072833D01*
X511813Y-1072917D01*
X511973Y-1073083D01*
X512080Y-1073375D01*
Y-1073708D01*
X512027Y-1074042D01*
X511920Y-1074292D01*
X511733Y-1074458D01*
X511573Y-1074500D01*
X511413Y-1074458D01*
X511253Y-1074333D01*
X511120Y-1074125D01*
G01X513800Y-1074500D02*
X513640Y-1074458D01*
X513480Y-1074292D01*
X513373Y-1074000D01*
X513320Y-1073667D01*
X513373Y-1073333D01*
X513480Y-1073042D01*
X513640Y-1072875D01*
X513800Y-1072833D01*
X513960Y-1072875D01*
X514120Y-1073042D01*
X514227Y-1073333D01*
X514253Y-1073667D01*
X514227Y-1074000D01*
X514120Y-1074292D01*
X513960Y-1074458D01*
X513800Y-1074500D01*
G01X516480D02*
Y-1072833D01*
G01Y-1073125D02*
X516373Y-1072958D01*
X516213Y-1072875D01*
X516027Y-1072833D01*
X515840Y-1072917D01*
X515680Y-1073083D01*
X515573Y-1073333D01*
X515520Y-1073667D01*
X515573Y-1074000D01*
X515680Y-1074250D01*
X515840Y-1074417D01*
X516027Y-1074500D01*
X516213Y-1074458D01*
X516373Y-1074333D01*
X516480Y-1074167D01*
G01X517827Y-1074500D02*
Y-1072833D01*
G01Y-1073167D02*
X517960Y-1073000D01*
X518093Y-1072875D01*
X518280Y-1072833D01*
X518413Y-1072875D01*
X518573Y-1073000D01*
G01X520880Y-1072000D02*
Y-1074500D01*
G01Y-1074125D02*
X520773Y-1074333D01*
X520613Y-1074458D01*
X520427Y-1074500D01*
X520213Y-1074417D01*
X520053Y-1074208D01*
X519947Y-1073958D01*
X519920Y-1073667D01*
X519947Y-1073375D01*
X520053Y-1073125D01*
X520213Y-1072917D01*
X520427Y-1072833D01*
X520613Y-1072875D01*
X520747Y-1072958D01*
X520880Y-1073125D01*
G01X524267Y-1074500D02*
Y-1072000D01*
X524933D01*
X525147Y-1072125D01*
X525280Y-1072292D01*
X525333Y-1072625D01*
X525280Y-1072958D01*
X525120Y-1073167D01*
X524933Y-1073292D01*
X524267D01*
G01X524933D02*
X525333Y-1074500D01*
G01X526600Y-1073375D02*
X527453D01*
X527373Y-1073083D01*
X527240Y-1072917D01*
X527053Y-1072833D01*
X526867Y-1072875D01*
X526707Y-1073000D01*
X526600Y-1073292D01*
X526547Y-1073542D01*
Y-1073792D01*
X526600Y-1074042D01*
X526733Y-1074292D01*
X526893Y-1074458D01*
X527080Y-1074500D01*
X527267Y-1074417D01*
X527453Y-1074167D01*
G01X528720Y-1072833D02*
X529200Y-1074500D01*
X529680Y-1072833D01*
G01X531400Y-1074583D02*
X531347Y-1074542D01*
Y-1074458D01*
X531400Y-1074417D01*
X531453Y-1074458D01*
Y-1074542D01*
X531400Y-1074583D01*
G01X533600Y-1074500D02*
X533787Y-1074458D01*
X534000Y-1074333D01*
X534133Y-1074125D01*
X534187Y-1073833D01*
X534133Y-1073542D01*
X533973Y-1073292D01*
X533733Y-1073167D01*
X533467D01*
X533307Y-1073083D01*
X533173Y-1072875D01*
X533120Y-1072583D01*
X533200Y-1072292D01*
X533387Y-1072083D01*
X533600Y-1072000D01*
X533813Y-1072083D01*
X534000Y-1072292D01*
X534080Y-1072583D01*
X534027Y-1072875D01*
X533893Y-1073083D01*
X533733Y-1073167D01*
X533467D01*
X533227Y-1073292D01*
X533067Y-1073542D01*
X533013Y-1073833D01*
X533067Y-1074125D01*
X533200Y-1074333D01*
X533413Y-1074458D01*
X533600Y-1074500D01*
G01X536013Y-1073167D02*
X536120Y-1073042D01*
X536200Y-1072833D01*
X536253Y-1072542D01*
X536200Y-1072292D01*
X536093Y-1072125D01*
X535907Y-1072000D01*
X535187D01*
Y-1074500D01*
X536067D01*
X536253Y-1074333D01*
X536360Y-1074083D01*
X536413Y-1073792D01*
X536360Y-1073500D01*
X536200Y-1073250D01*
X536013Y-1073167D01*
X535187D01*
G01X742126Y64961D02*
Y71007D01*
G03X739703Y79400I-15749J0D01*
G02X756360I8329J5246D01*
G03X753937Y71007I13326J-8393D01*
G01Y64961D01*
G02X742126I-5905J0D01*
G01Y71007D02*
G03X739703Y79400I-15749J0D01*
G02X756360I8329J5246D01*
G03X753937Y71007I13326J-8393D01*
G01Y64961D01*
G02X742126I-5905J0D01*
G01Y71007D01*
G01X753937Y344488D02*
G02X742126I-5905J0D01*
G01Y350535D01*
G03X739703Y358928I-15749J0D01*
G02X756360I8329J5246D01*
G03X753937Y350535I13326J-8393D01*
G01Y344488D01*
G01X742126D02*
Y350535D01*
G03X739703Y358928I-15749J0D01*
G02X756360I8329J5246D01*
G03X753937Y350535I13326J-8393D01*
G01Y344488D01*
G02X742126I-5905J0D01*
G01X813780Y88465D02*
G02X830394I8307J0D01*
G02X813780I-8307J0D01*
G01D02*
G02X830394I8307J0D01*
G02X813780I-8307J0D01*
G01Y313504D02*
G02X830394I8307J0D01*
G02X813780I-8307J0D01*
G01D02*
G02X830394I8307J0D01*
G02X813780I-8307J0D01*
G01X931890Y88465D02*
G02X948504I8307J0D01*
G02X931890I-8307J0D01*
G01D02*
G02X948504I8307J0D01*
G02X931890I-8307J0D01*
G01Y313504D02*
G02X948504I8307J0D01*
G02X931890I-8307J0D01*
G01D02*
G02X948504I8307J0D01*
G02X931890I-8307J0D01*
G01X978346Y64961D02*
Y71007D01*
G03X975924Y79400I-15748J1D01*
G02X992580I8328J5245D01*
G03X990157Y71007I13326J-8393D01*
G01Y64961D01*
G02X978346I-5906J0D01*
G01Y71007D02*
G03X975924Y79400I-15748J1D01*
G02X992580I8328J5245D01*
G03X990157Y71007I13326J-8393D01*
G01Y64961D01*
G02X978346I-5906J0D01*
G01Y71007D01*
G01Y344488D02*
Y350535D01*
G03X975924Y358928I-15748J1D01*
G02X992580I8328J5245D01*
G03X990157Y350535I13326J-8393D01*
G01Y344488D01*
G02X978346I-5906J0D01*
G01Y350535D02*
G03X975924Y358928I-15748J1D01*
G02X992580I8328J5245D01*
G03X990157Y350535I13326J-8393D01*
G01Y344488D01*
G02X978346I-5906J0D01*
G01Y350535D01*
G01X1344488Y344488D02*
G02X1332677I-5905J0D01*
G01Y350535D01*
G03X1330254Y358928I-15749J0D01*
G02X1346911I8329J5246D01*
G03X1344488Y350535I13326J-8393D01*
G01Y344488D01*
G01X1332677D02*
Y350535D01*
G03X1330254Y358928I-15749J0D01*
G02X1346911I8329J5246D01*
G03X1344488Y350535I13326J-8393D01*
G01Y344488D01*
G02X1332677I-5905J0D01*
G01X1426693Y15512D02*
G02X1436142I4724J0D01*
G02X1426693I-4725J0D01*
G01D02*
G02X1436142I4724J0D01*
G02X1426693I-4725J0D01*
G01X1423228Y561024D02*
G02X1411417I-5906J0D01*
G01Y567070D01*
G03X1408995Y575463I-15748J1D01*
G02X1425651I8328J5245D01*
G03X1423228Y567070I13326J-8393D01*
G01Y561024D01*
G01X1411417D02*
Y567070D01*
G03X1408995Y575463I-15748J1D01*
G02X1425651I8328J5245D01*
G03X1423228Y567070I13326J-8393D01*
G01Y561024D01*
G02X1411417I-5906J0D01*
G01X1446850Y53150D02*
Y59196D01*
G03X1444428Y67589I-15748J1D01*
G02X1461084I8328J5245D01*
G03X1458661Y59196I13326J-8393D01*
G01Y53150D01*
G02X1446850I-5905J0D01*
G01Y59196D02*
G03X1444428Y67589I-15748J1D01*
G02X1461084I8328J5245D01*
G03X1458661Y59196I13326J-8393D01*
G01Y53150D01*
G02X1446850I-5905J0D01*
G01Y59196D01*
G01X1464370Y628465D02*
G02X1472638I4134J0D01*
G02X1464370I-4134J0D01*
G01D02*
G02X1472638I4134J0D01*
G02X1464370I-4134J0D01*
G01X1440748Y659961D02*
G02X1449016I4134J0D01*
G02X1440748I-4134J0D01*
G01D02*
G02X1449016I4134J0D01*
G02X1440748I-4134J0D01*
G01X1486693Y10197D02*
G02X1496142I4725J0D01*
G02X1486693I-4725J0D01*
G01D02*
G02X1496142I4725J0D01*
G02X1486693I-4725J0D01*
G01X1520226Y639094D02*
G02X1528593I4183J0D01*
G02X1520226I-4184J0D01*
G01D02*
G02X1528593I4183J0D01*
G02X1520226I-4184J0D01*
G01X1679134Y17717D02*
Y23763D01*
G03X1676711Y32156I-15749J0D01*
G02X1693368I8329J5246D01*
G03X1690945Y23763I13326J-8393D01*
G01Y17717D01*
G02X1679134I-5905J0D01*
G01Y23763D02*
G03X1676711Y32156I-15749J0D01*
G02X1693368I8329J5246D01*
G03X1690945Y23763I13326J-8393D01*
G01Y17717D01*
G02X1679134I-5905J0D01*
G01Y23763D01*
G01X1665354Y236614D02*
G02X1681102I7874J0D01*
G02X1665354I-7874J0D01*
G01D02*
G02X1681102I7874J0D01*
G02X1665354I-7874J0D01*
G01X1679134Y330709D02*
Y336756D01*
G03X1676711Y345148I-15747J-1D01*
G02X1693368I8329J5246D01*
G03X1690945Y336756I13324J-8393D01*
G01Y330709D01*
G02X1679134I-5905J0D01*
G01Y336756D02*
G03X1676711Y345148I-15747J-1D01*
G02X1693368I8329J5246D01*
G03X1690945Y336756I13324J-8393D01*
G01Y330709D01*
G02X1679134I-5905J0D01*
G01Y336756D01*
G01X1665354Y411614D02*
G02X1681102I7874J0D01*
G02X1665354I-7874J0D01*
G01D02*
G02X1681102I7874J0D01*
G02X1665354I-7874J0D01*
G01X1660630Y498031D02*
G02X1685827I12599J0D01*
G02X1660630I-12599J0D01*
G01D02*
G02X1685827I12599J0D01*
G02X1660630I-12599J0D01*
G01X1687402Y541339D02*
G02X1712598I12598J0D01*
G02X1687402I-12598J0D01*
G01D02*
G02X1712598I12598J0D01*
G02X1687402I-12598J0D01*
G01X1805118Y96457D02*
G02X1793307I-5906J0D01*
G01Y102504D01*
G03X1790884Y110896I-15747J-1D01*
G02X1807541I8329J5246D01*
G03X1805118Y102504I13324J-8393D01*
G01Y96457D01*
G01X1793307D02*
Y102504D01*
G03X1790884Y110896I-15747J-1D01*
G02X1807541I8329J5246D01*
G03X1805118Y102504I13324J-8393D01*
G01Y96457D01*
G02X1793307I-5906J0D01*
G01X1805118Y478346D02*
G02X1793307I-5906J0D01*
G01Y484393D01*
G03X1790884Y492786I-15749J0D01*
G02X1807541I8329J5246D01*
G03X1805118Y484393I13326J-8393D01*
G01Y478346D01*
G01X1793307D02*
Y484393D01*
G03X1790884Y492786I-15749J0D01*
G02X1807541I8329J5246D01*
G03X1805118Y484393I13326J-8393D01*
G01Y478346D01*
G02X1793307I-5906J0D01*
G01X1839865Y94037D02*
G03X1836480Y95965I-3386J-2009D01*
G01X1833031D01*
G02X1830079Y98917I0J2952D01*
G01Y99508D01*
G02X1833031Y102461I2952J1D01*
G01X1836480D01*
G03X1839865Y104388I0J3937D01*
G02Y94037I8718J-5176D01*
G01D02*
G03X1836480Y95965I-3386J-2009D01*
G01X1833031D01*
G02X1830079Y98917I0J2952D01*
G01Y99508D01*
G02X1833031Y102461I2952J1D01*
G01X1836480D01*
G03X1839865Y104388I0J3937D01*
G02Y94037I8718J-5176D01*
G01Y476518D02*
G03X1836480Y478445I-3385J-2010D01*
G01X1833031D01*
G02X1830079Y481398I0J2953D01*
G01Y481988D01*
G02X1833031Y484941I2952J0D01*
G01X1836480D01*
G03X1839865Y486868I0J3937D01*
G02Y476518I8717J-5175D01*
G01D02*
G03X1836480Y478445I-3385J-2010D01*
G01X1833031D01*
G02X1830079Y481398I0J2953D01*
G01Y481988D01*
G02X1833031Y484941I2953J0D01*
G01X1836480D01*
G03X1839865Y486868I0J3937D01*
G02Y476518I8717J-5175D01*
G01X-457143Y-1211429D02*
Y2242857D01*
X4308572D01*
Y-1211429D01*
X-457143D01*
G01X90551Y236614D02*
G03I-31496J0D01*
G01Y411594D02*
G03I-31496J0D01*
G01X71650Y-1024800D02*
X69130Y-1024383D01*
X66925Y-1022717D01*
X65035Y-1020217D01*
X63775Y-1017300D01*
X63145Y-1013967D01*
Y-1010633D01*
X63775Y-1007300D01*
X65035Y-1004383D01*
X66925Y-1001884D01*
X69130Y-1000217D01*
X71650Y-999800D01*
X74170Y-1000217D01*
X76375Y-1001884D01*
X78265Y-1004383D01*
X79525Y-1007300D01*
X80155Y-1010633D01*
Y-1013967D01*
X79525Y-1017300D01*
X78265Y-1020217D01*
X76375Y-1022717D01*
X74170Y-1024383D01*
X71650Y-1024800D01*
G01X74170Y-1018133D02*
X77950Y-1024800D01*
G01X91495Y-1008134D02*
Y-1019800D01*
X92755Y-1022717D01*
X94645Y-1024383D01*
X96850Y-1024800D01*
X99055Y-1024383D01*
X100945Y-1022717D01*
X102205Y-1019800D01*
G01Y-1024800D02*
Y-1008134D01*
G01X127720Y-1024800D02*
Y-1008134D01*
G01Y-1011050D02*
X126460Y-1009384D01*
X124570Y-1008550D01*
X122365Y-1008134D01*
X120160Y-1008967D01*
X118270Y-1010633D01*
X117010Y-1013134D01*
X116380Y-1016467D01*
X117010Y-1019800D01*
X118270Y-1022301D01*
X120160Y-1023967D01*
X122365Y-1024800D01*
X124570Y-1024383D01*
X126460Y-1023134D01*
X127720Y-1021467D01*
G01X141895Y-1024800D02*
Y-1008134D01*
G01Y-1012300D02*
X143155Y-1010217D01*
X145045Y-1008550D01*
X147565Y-1008134D01*
X149770Y-1008550D01*
X151660Y-1010217D01*
X152605Y-1013134D01*
Y-1024800D01*
G01X172450Y-999800D02*
Y-1024800D01*
G01X168040Y-1008134D02*
X176860D01*
G01X203320Y-1024800D02*
Y-1008134D01*
G01Y-1011050D02*
X202060Y-1009384D01*
X200170Y-1008550D01*
X197965Y-1008134D01*
X195760Y-1008967D01*
X193870Y-1010633D01*
X192610Y-1013134D01*
X191980Y-1016467D01*
X192610Y-1019800D01*
X193870Y-1022301D01*
X195760Y-1023967D01*
X197965Y-1024800D01*
X200170Y-1024383D01*
X202060Y-1023134D01*
X203320Y-1021467D01*
G01X49820Y-1042350D02*
X51387D01*
Y-1044240D01*
X50917Y-1044870D01*
X50368Y-1045290D01*
X49585Y-1045500D01*
X48802Y-1045290D01*
X48253Y-1044870D01*
X47783Y-1044240D01*
X47470Y-1043505D01*
X47313Y-1042665D01*
Y-1041930D01*
X47470Y-1041300D01*
X47783Y-1040565D01*
X48253Y-1039935D01*
X48723Y-1039515D01*
X49350Y-1039200D01*
X49898D01*
X50525Y-1039410D01*
X50995Y-1039830D01*
G01X53927Y-1039200D02*
Y-1043715D01*
X54240Y-1044660D01*
X54867Y-1045290D01*
X55650Y-1045500D01*
X56433Y-1045290D01*
X57060Y-1044660D01*
X57373Y-1043715D01*
Y-1039200D01*
G01X61010D02*
X62890D01*
G01X61950D02*
Y-1045500D01*
G01X61010D02*
X62890D01*
G01X66605Y-1044660D02*
X67232Y-1045185D01*
X67937Y-1045500D01*
X68563D01*
X69190Y-1045185D01*
X69660Y-1044660D01*
X69895Y-1043925D01*
X69738Y-1043190D01*
X69347Y-1042560D01*
X68642Y-1042140D01*
X67702Y-1041930D01*
X67153Y-1041510D01*
X66918Y-1040775D01*
X67075Y-1040040D01*
X67467Y-1039515D01*
X68015Y-1039200D01*
X68563D01*
X69112Y-1039410D01*
X69582Y-1039935D01*
G01X72905Y-1045500D02*
Y-1039200D01*
G01X76195D02*
Y-1045500D01*
G01Y-1042350D02*
X72905D01*
G01X78892Y-1045500D02*
X80850Y-1039200D01*
X82808Y-1045500D01*
G01X82103Y-1043295D02*
X79597D01*
G01X85348Y-1045500D02*
Y-1039200D01*
X88952Y-1045500D01*
Y-1039200D01*
G01X98027Y-1045500D02*
Y-1039200D01*
X99593D01*
X100220Y-1039515D01*
X100690Y-1039935D01*
X101082Y-1040565D01*
X101395Y-1041300D01*
X101473Y-1042350D01*
X101395Y-1043400D01*
X101082Y-1044135D01*
X100690Y-1044765D01*
X100220Y-1045185D01*
X99593Y-1045500D01*
X98027D01*
G01X105110Y-1039200D02*
X106990D01*
G01X106050D02*
Y-1045500D01*
G01X105110D02*
X106990D01*
G01X110705Y-1044660D02*
X111332Y-1045185D01*
X112037Y-1045500D01*
X112663D01*
X113290Y-1045185D01*
X113760Y-1044660D01*
X113995Y-1043925D01*
X113838Y-1043190D01*
X113447Y-1042560D01*
X112742Y-1042140D01*
X111802Y-1041930D01*
X111253Y-1041510D01*
X111018Y-1040775D01*
X111175Y-1040040D01*
X111567Y-1039515D01*
X112115Y-1039200D01*
X112663D01*
X113212Y-1039410D01*
X113682Y-1039935D01*
G01X118650Y-1039200D02*
Y-1045500D01*
G01X116848Y-1039200D02*
X120452D01*
G01X124950Y-1045710D02*
X124793Y-1045605D01*
Y-1045395D01*
X124950Y-1045290D01*
X125107Y-1045395D01*
Y-1045605D01*
X124950Y-1045710D01*
G01X131093Y-1046655D02*
X131407Y-1045290D01*
G01X137550Y-1039200D02*
Y-1045500D01*
G01X135748Y-1039200D02*
X139352D01*
G01X141892Y-1045500D02*
X143850Y-1039200D01*
X145808Y-1045500D01*
G01X145103Y-1043295D02*
X142597D01*
G01X150150Y-1045500D02*
X149523Y-1045395D01*
X148975Y-1044975D01*
X148505Y-1044345D01*
X148192Y-1043610D01*
X148035Y-1042770D01*
Y-1041930D01*
X148192Y-1041090D01*
X148505Y-1040355D01*
X148975Y-1039725D01*
X149523Y-1039305D01*
X150150Y-1039200D01*
X150777Y-1039305D01*
X151325Y-1039725D01*
X151795Y-1040355D01*
X152108Y-1041090D01*
X152265Y-1041930D01*
Y-1042770D01*
X152108Y-1043610D01*
X151795Y-1044345D01*
X151325Y-1044975D01*
X150777Y-1045395D01*
X150150Y-1045500D01*
G01X156450D02*
Y-1042665D01*
X154883Y-1039200D01*
G01X158017D02*
X156450Y-1042665D01*
G01X161027Y-1039200D02*
Y-1043715D01*
X161340Y-1044660D01*
X161967Y-1045290D01*
X162750Y-1045500D01*
X163533Y-1045290D01*
X164160Y-1044660D01*
X164473Y-1043715D01*
Y-1039200D01*
G01X167092Y-1045500D02*
X169050Y-1039200D01*
X171008Y-1045500D01*
G01X170303Y-1043295D02*
X167797D01*
G01X173548Y-1045500D02*
Y-1039200D01*
X177152Y-1045500D01*
Y-1039200D01*
G01X51073Y-1049725D02*
X50603Y-1049410D01*
X50055Y-1049200D01*
X49428D01*
X48723Y-1049515D01*
X48175Y-1050040D01*
X47783Y-1050670D01*
X47470Y-1051720D01*
X47392Y-1052665D01*
X47548Y-1053610D01*
X47783Y-1054240D01*
X48253Y-1054870D01*
X48802Y-1055290D01*
X49350Y-1055500D01*
X49898D01*
X50447Y-1055290D01*
X50917Y-1054975D01*
X51308Y-1054555D01*
G01X54710Y-1049200D02*
X56590D01*
G01X55650D02*
Y-1055500D01*
G01X54710D02*
X56590D01*
G01X61950Y-1049200D02*
Y-1055500D01*
G01X60148Y-1049200D02*
X63752D01*
G01X68250Y-1055500D02*
Y-1052665D01*
X66683Y-1049200D01*
G01X69817D02*
X68250Y-1052665D01*
G01X79127Y-1054240D02*
X79597Y-1054975D01*
X80223Y-1055395D01*
X80928Y-1055500D01*
X81555Y-1055395D01*
X82182Y-1054870D01*
X82573Y-1054240D01*
X82652Y-1053610D01*
X82495Y-1052875D01*
X81947Y-1052350D01*
X81398Y-1052140D01*
X80693D01*
G01X81398D02*
X81868Y-1051825D01*
X82260Y-1051300D01*
X82417Y-1050670D01*
X82260Y-1050040D01*
X81868Y-1049515D01*
X81163Y-1049200D01*
X80458Y-1049305D01*
X79753Y-1049725D01*
G01X85427Y-1054240D02*
X85897Y-1054975D01*
X86523Y-1055395D01*
X87228Y-1055500D01*
X87855Y-1055395D01*
X88482Y-1054870D01*
X88873Y-1054240D01*
X88952Y-1053610D01*
X88795Y-1052875D01*
X88247Y-1052350D01*
X87698Y-1052140D01*
X86993D01*
G01X87698D02*
X88168Y-1051825D01*
X88560Y-1051300D01*
X88717Y-1050670D01*
X88560Y-1050040D01*
X88168Y-1049515D01*
X87463Y-1049200D01*
X86758Y-1049305D01*
X86053Y-1049725D01*
G01X91727Y-1054240D02*
X92197Y-1054975D01*
X92823Y-1055395D01*
X93528Y-1055500D01*
X94155Y-1055395D01*
X94782Y-1054870D01*
X95173Y-1054240D01*
X95252Y-1053610D01*
X95095Y-1052875D01*
X94547Y-1052350D01*
X93998Y-1052140D01*
X93293D01*
G01X93998D02*
X94468Y-1051825D01*
X94860Y-1051300D01*
X95017Y-1050670D01*
X94860Y-1050040D01*
X94468Y-1049515D01*
X93763Y-1049200D01*
X93058Y-1049305D01*
X92353Y-1049725D01*
G01X99593Y-1055500D02*
X99750Y-1054135D01*
X99985Y-1052980D01*
X100298Y-1051930D01*
X100690Y-1050775D01*
X101317Y-1049200D01*
X98183D01*
G01X105893Y-1055500D02*
X106050Y-1054135D01*
X106285Y-1052980D01*
X106598Y-1051930D01*
X106990Y-1050775D01*
X107617Y-1049200D01*
X104483D01*
G01X112193Y-1056655D02*
X112507Y-1055290D01*
G01X118650Y-1049200D02*
Y-1055500D01*
G01X116848Y-1049200D02*
X120452D01*
G01X122992Y-1055500D02*
X124950Y-1049200D01*
X126908Y-1055500D01*
G01X126203Y-1053295D02*
X123697D01*
G01X130310Y-1049200D02*
X132190D01*
G01X131250D02*
Y-1055500D01*
G01X130310D02*
X132190D01*
G01X135200Y-1049200D02*
X136297Y-1055500D01*
X137550Y-1049200D01*
X138803Y-1055500D01*
X139900Y-1049200D01*
G01X141892Y-1055500D02*
X143850Y-1049200D01*
X145808Y-1055500D01*
G01X145103Y-1053295D02*
X142597D01*
G01X148348Y-1055500D02*
Y-1049200D01*
X151952Y-1055500D01*
Y-1049200D01*
G01X162358Y-1057600D02*
X161575Y-1056550D01*
X161183Y-1055500D01*
Y-1051300D01*
X161575Y-1050250D01*
X162358Y-1049200D01*
G01X173783Y-1055500D02*
Y-1049200D01*
X175742D01*
X176368Y-1049515D01*
X176760Y-1049935D01*
X176917Y-1050775D01*
X176760Y-1051615D01*
X176290Y-1052140D01*
X175742Y-1052455D01*
X173783D01*
G01X175742D02*
X176917Y-1055500D01*
G01X181650Y-1055710D02*
X181493Y-1055605D01*
Y-1055395D01*
X181650Y-1055290D01*
X181807Y-1055395D01*
Y-1055605D01*
X181650Y-1055710D01*
G01X187950Y-1055500D02*
X187323Y-1055395D01*
X186775Y-1054975D01*
X186305Y-1054345D01*
X185992Y-1053610D01*
X185835Y-1052770D01*
Y-1051930D01*
X185992Y-1051090D01*
X186305Y-1050355D01*
X186775Y-1049725D01*
X187323Y-1049305D01*
X187950Y-1049200D01*
X188577Y-1049305D01*
X189125Y-1049725D01*
X189595Y-1050355D01*
X189908Y-1051090D01*
X190065Y-1051930D01*
Y-1052770D01*
X189908Y-1053610D01*
X189595Y-1054345D01*
X189125Y-1054975D01*
X188577Y-1055395D01*
X187950Y-1055500D01*
G01X194250Y-1055710D02*
X194093Y-1055605D01*
Y-1055395D01*
X194250Y-1055290D01*
X194407Y-1055395D01*
Y-1055605D01*
X194250Y-1055710D01*
G01X202273Y-1049725D02*
X201803Y-1049410D01*
X201255Y-1049200D01*
X200628D01*
X199923Y-1049515D01*
X199375Y-1050040D01*
X198983Y-1050670D01*
X198670Y-1051720D01*
X198592Y-1052665D01*
X198748Y-1053610D01*
X198983Y-1054240D01*
X199453Y-1054870D01*
X200002Y-1055290D01*
X200550Y-1055500D01*
X201098D01*
X201647Y-1055290D01*
X202117Y-1054975D01*
X202508Y-1054555D01*
G01X206850Y-1055710D02*
X206693Y-1055605D01*
Y-1055395D01*
X206850Y-1055290D01*
X207007Y-1055395D01*
Y-1055605D01*
X206850Y-1055710D01*
G01X213542Y-1057600D02*
X214325Y-1056550D01*
X214717Y-1055500D01*
Y-1051300D01*
X214325Y-1050250D01*
X213542Y-1049200D01*
G01X47548Y-1035500D02*
Y-1029200D01*
X51152Y-1035500D01*
Y-1029200D01*
G01X55650Y-1035500D02*
X55023Y-1035395D01*
X54475Y-1034975D01*
X54005Y-1034345D01*
X53692Y-1033610D01*
X53535Y-1032770D01*
Y-1031930D01*
X53692Y-1031090D01*
X54005Y-1030355D01*
X54475Y-1029725D01*
X55023Y-1029305D01*
X55650Y-1029200D01*
X56277Y-1029305D01*
X56825Y-1029725D01*
X57295Y-1030355D01*
X57608Y-1031090D01*
X57765Y-1031930D01*
Y-1032770D01*
X57608Y-1033610D01*
X57295Y-1034345D01*
X56825Y-1034975D01*
X56277Y-1035395D01*
X55650Y-1035500D01*
G01X61950Y-1035710D02*
X61793Y-1035605D01*
Y-1035395D01*
X61950Y-1035290D01*
X62107Y-1035395D01*
Y-1035605D01*
X61950Y-1035710D01*
G01X66762Y-1030250D02*
X67232Y-1029620D01*
X67780Y-1029305D01*
X68407Y-1029200D01*
X69190Y-1029410D01*
X69738Y-1029935D01*
X69895Y-1030565D01*
X69817Y-1031195D01*
X69503Y-1031720D01*
X67937Y-1032770D01*
X67232Y-1033505D01*
X66762Y-1034555D01*
X66605Y-1035500D01*
X69895D01*
G01X74550D02*
Y-1029200D01*
X73610Y-1030460D01*
G01Y-1035500D02*
X75490D01*
G01X80850D02*
Y-1029200D01*
X79910Y-1030460D01*
G01Y-1035500D02*
X81790D01*
G01X86993Y-1036655D02*
X87307Y-1035290D01*
G01X91100Y-1029200D02*
X92197Y-1035500D01*
X93450Y-1029200D01*
X94703Y-1035500D01*
X95800Y-1029200D01*
G01X101317Y-1035500D02*
X98183D01*
Y-1029200D01*
X101317D01*
G01X100063Y-1032245D02*
X98183D01*
G01X104248Y-1035500D02*
Y-1029200D01*
X107852Y-1035500D01*
Y-1029200D01*
G01X110705Y-1035500D02*
Y-1029200D01*
G01X113995D02*
Y-1035500D01*
G01Y-1032350D02*
X110705D01*
G01X116927Y-1029200D02*
Y-1033715D01*
X117240Y-1034660D01*
X117867Y-1035290D01*
X118650Y-1035500D01*
X119433Y-1035290D01*
X120060Y-1034660D01*
X120373Y-1033715D01*
Y-1029200D01*
G01X122992Y-1035500D02*
X124950Y-1029200D01*
X126908Y-1035500D01*
G01X126203Y-1033295D02*
X123697D01*
G01X136062Y-1030250D02*
X136532Y-1029620D01*
X137080Y-1029305D01*
X137707Y-1029200D01*
X138490Y-1029410D01*
X139038Y-1029935D01*
X139195Y-1030565D01*
X139117Y-1031195D01*
X138803Y-1031720D01*
X137237Y-1032770D01*
X136532Y-1033505D01*
X136062Y-1034555D01*
X135905Y-1035500D01*
X139195D01*
G01X142048D02*
Y-1029200D01*
X145652Y-1035500D01*
Y-1029200D01*
G01X148427Y-1035500D02*
Y-1029200D01*
X149993D01*
X150620Y-1029515D01*
X151090Y-1029935D01*
X151482Y-1030565D01*
X151795Y-1031300D01*
X151873Y-1032350D01*
X151795Y-1033400D01*
X151482Y-1034135D01*
X151090Y-1034765D01*
X150620Y-1035185D01*
X149993Y-1035500D01*
X148427D01*
G01X161183D02*
Y-1029200D01*
X163142D01*
X163768Y-1029515D01*
X164160Y-1029935D01*
X164317Y-1030775D01*
X164160Y-1031615D01*
X163690Y-1032140D01*
X163142Y-1032455D01*
X161183D01*
G01X163142D02*
X164317Y-1035500D01*
G01X167327D02*
Y-1029200D01*
X168893D01*
X169520Y-1029515D01*
X169990Y-1029935D01*
X170382Y-1030565D01*
X170695Y-1031300D01*
X170773Y-1032350D01*
X170695Y-1033400D01*
X170382Y-1034135D01*
X169990Y-1034765D01*
X169520Y-1035185D01*
X168893Y-1035500D01*
X167327D01*
G01X175350Y-1035710D02*
X175193Y-1035605D01*
Y-1035395D01*
X175350Y-1035290D01*
X175507Y-1035395D01*
Y-1035605D01*
X175350Y-1035710D01*
G01X124600Y600933D02*
X132100D01*
Y603173D01*
X131725Y603920D01*
X130850Y604480D01*
X129850Y604667D01*
X128850Y604480D01*
X128100Y604013D01*
X127725Y603173D01*
Y600933D01*
G01X124600Y608433D02*
X132100D01*
Y610767D01*
X131725Y611513D01*
X131225Y611980D01*
X130225Y612167D01*
X129225Y611980D01*
X128600Y611420D01*
X128225Y610767D01*
Y608433D01*
G01Y610767D02*
X124600Y612167D01*
G01Y619667D02*
Y615933D01*
X132100D01*
Y619667D01*
G01X128475Y618173D02*
Y615933D01*
G01X125600Y623340D02*
X124975Y624087D01*
X124600Y624927D01*
Y625673D01*
X124975Y626420D01*
X125600Y626980D01*
X126475Y627260D01*
X127350Y627073D01*
X128100Y626607D01*
X128600Y625767D01*
X128850Y624647D01*
X129350Y623993D01*
X130225Y623713D01*
X131100Y623900D01*
X131725Y624367D01*
X132100Y625020D01*
Y625673D01*
X131850Y626327D01*
X131225Y626887D01*
G01X125600Y630840D02*
X124975Y631587D01*
X124600Y632427D01*
Y633173D01*
X124975Y633920D01*
X125600Y634480D01*
X126475Y634760D01*
X127350Y634573D01*
X128100Y634107D01*
X128600Y633267D01*
X128850Y632147D01*
X129350Y631493D01*
X130225Y631213D01*
X131100Y631400D01*
X131725Y631867D01*
X132100Y632520D01*
Y633173D01*
X131850Y633827D01*
X131225Y634387D01*
G01X127100Y639087D02*
Y641513D01*
G01X124600Y646027D02*
X132100D01*
Y649573D01*
G01X128475Y648267D02*
Y646027D01*
G01X132100Y654180D02*
Y656420D01*
G01Y655300D02*
X124600D01*
G01Y654180D02*
Y656420D01*
G01X132100Y662800D02*
X124600D01*
G01X132100Y660653D02*
Y664947D01*
G01X112205Y738307D02*
X188976D01*
Y582008D01*
X112205D01*
Y738307D01*
G01X174600Y599933D02*
X182100D01*
Y602173D01*
X181725Y602920D01*
X180850Y603480D01*
X179850Y603667D01*
X178850Y603480D01*
X178100Y603013D01*
X177725Y602173D01*
Y599933D01*
G01X174600Y607433D02*
X182100D01*
Y609767D01*
X181725Y610513D01*
X181225Y610980D01*
X180225Y611167D01*
X179225Y610980D01*
X178600Y610420D01*
X178225Y609767D01*
Y607433D01*
G01Y609767D02*
X174600Y611167D01*
G01Y618667D02*
Y614933D01*
X182100D01*
Y618667D01*
G01X178475Y617173D02*
Y614933D01*
G01X175600Y622340D02*
X174975Y623087D01*
X174600Y623927D01*
Y624673D01*
X174975Y625420D01*
X175600Y625980D01*
X176475Y626260D01*
X177350Y626073D01*
X178100Y625607D01*
X178600Y624767D01*
X178850Y623647D01*
X179350Y622993D01*
X180225Y622713D01*
X181100Y622900D01*
X181725Y623367D01*
X182100Y624020D01*
Y624673D01*
X181850Y625327D01*
X181225Y625887D01*
G01X175600Y629840D02*
X174975Y630587D01*
X174600Y631427D01*
Y632173D01*
X174975Y632920D01*
X175600Y633480D01*
X176475Y633760D01*
X177350Y633573D01*
X178100Y633107D01*
X178600Y632267D01*
X178850Y631147D01*
X179350Y630493D01*
X180225Y630213D01*
X181100Y630400D01*
X181725Y630867D01*
X182100Y631520D01*
Y632173D01*
X181850Y632827D01*
X181225Y633387D01*
G01X177100Y638087D02*
Y640513D01*
G01X174600Y645027D02*
X182100D01*
Y648573D01*
G01X178475Y647267D02*
Y645027D01*
G01X182100Y653180D02*
Y655420D01*
G01Y654300D02*
X174600D01*
G01Y653180D02*
Y655420D01*
G01X182100Y661800D02*
X174600D01*
G01X182100Y659653D02*
Y663947D01*
G01X172736Y590473D02*
Y729449D01*
G01X243012Y590473D02*
X172736D01*
G01Y729449D02*
X243012D01*
G01X321122Y41595D02*
Y-10571D01*
X220611D01*
Y41595D01*
X321122D01*
G01X257550Y81000D02*
G03I-25950J0D01*
G01X254400Y-1036434D02*
X255200Y-1037100D01*
X256100Y-1037500D01*
X256900D01*
X257700Y-1037100D01*
X258300Y-1036434D01*
X258600Y-1035500D01*
X258400Y-1034567D01*
X257900Y-1033767D01*
X257000Y-1033233D01*
X255800Y-1032967D01*
X255100Y-1032433D01*
X254800Y-1031500D01*
X255000Y-1030567D01*
X255500Y-1029900D01*
X256200Y-1029500D01*
X256900D01*
X257600Y-1029767D01*
X258200Y-1030433D01*
G01X263300Y-1029500D02*
X265700D01*
G01X264500D02*
Y-1037500D01*
G01X263300D02*
X265700D01*
G01X270500Y-1029500D02*
Y-1037500D01*
X274500D01*
G01X278300D02*
Y-1029500D01*
G01X282100D02*
X278300Y-1034434D01*
G01X282700Y-1037500D02*
X280000Y-1032167D01*
G01X287200Y-1034833D02*
X289800D01*
G01X297300Y-1033233D02*
X297700Y-1032833D01*
X298000Y-1032167D01*
X298200Y-1031233D01*
X298000Y-1030433D01*
X297600Y-1029900D01*
X296900Y-1029500D01*
X294200D01*
Y-1037500D01*
X297500D01*
X298200Y-1036967D01*
X298600Y-1036167D01*
X298800Y-1035233D01*
X298600Y-1034300D01*
X298000Y-1033500D01*
X297300Y-1033233D01*
X294200D01*
G01X304500Y-1037500D02*
X303700Y-1037367D01*
X303000Y-1036833D01*
X302400Y-1036033D01*
X302000Y-1035100D01*
X301800Y-1034033D01*
Y-1032967D01*
X302000Y-1031900D01*
X302400Y-1030967D01*
X303000Y-1030167D01*
X303700Y-1029633D01*
X304500Y-1029500D01*
X305300Y-1029633D01*
X306000Y-1030167D01*
X306600Y-1030967D01*
X307000Y-1031900D01*
X307200Y-1032967D01*
Y-1034033D01*
X307000Y-1035100D01*
X306600Y-1036033D01*
X306000Y-1036833D01*
X305300Y-1037367D01*
X304500Y-1037500D01*
G01X312500Y-1029500D02*
Y-1037500D01*
G01X310200Y-1029500D02*
X314800D01*
G01X243000Y-1004500D02*
Y-1012500D01*
X247000D01*
G01X254800D02*
Y-1007167D01*
G01Y-1008100D02*
X254400Y-1007567D01*
X253800Y-1007300D01*
X253100Y-1007167D01*
X252400Y-1007433D01*
X251800Y-1007967D01*
X251400Y-1008767D01*
X251200Y-1009833D01*
X251400Y-1010900D01*
X251800Y-1011700D01*
X252400Y-1012233D01*
X253100Y-1012500D01*
X253800Y-1012367D01*
X254400Y-1011967D01*
X254800Y-1011434D01*
G01X258900Y-1014900D02*
X259500Y-1015167D01*
X260300Y-1014900D01*
X260800Y-1014367D01*
X261200Y-1013700D01*
X261800Y-1011567D01*
X263100Y-1007167D01*
G01X259900D02*
X261800Y-1011567D01*
G01X267500Y-1008900D02*
X270700D01*
X270400Y-1007967D01*
X269900Y-1007433D01*
X269200Y-1007167D01*
X268500Y-1007300D01*
X267900Y-1007700D01*
X267500Y-1008633D01*
X267300Y-1009434D01*
Y-1010233D01*
X267500Y-1011033D01*
X268000Y-1011833D01*
X268600Y-1012367D01*
X269300Y-1012500D01*
X270000Y-1012233D01*
X270700Y-1011434D01*
G01X275600Y-1012500D02*
Y-1007167D01*
G01Y-1008233D02*
X276100Y-1007700D01*
X276600Y-1007300D01*
X277300Y-1007167D01*
X277800Y-1007300D01*
X278400Y-1007700D01*
G01X300667Y26500D02*
Y34000D01*
X298427D01*
X297680Y33625D01*
X297120Y32750D01*
X296933Y31750D01*
X297120Y30750D01*
X297587Y30000D01*
X298427Y29625D01*
X300667D01*
G01X293167Y26500D02*
Y34000D01*
X290833D01*
X290087Y33625D01*
X289620Y33125D01*
X289433Y32125D01*
X289620Y31125D01*
X290180Y30500D01*
X290833Y30125D01*
X293167D01*
G01X290833D02*
X289433Y26500D01*
G01X281933D02*
X285667D01*
Y34000D01*
X281933D01*
G01X283427Y30375D02*
X285667D01*
G01X278260Y27500D02*
X277513Y26875D01*
X276673Y26500D01*
X275927D01*
X275180Y26875D01*
X274620Y27500D01*
X274340Y28375D01*
X274527Y29250D01*
X274993Y30000D01*
X275833Y30500D01*
X276953Y30750D01*
X277607Y31250D01*
X277887Y32125D01*
X277700Y33000D01*
X277233Y33625D01*
X276580Y34000D01*
X275927D01*
X275273Y33750D01*
X274713Y33125D01*
G01X270760Y27500D02*
X270013Y26875D01*
X269173Y26500D01*
X268427D01*
X267680Y26875D01*
X267120Y27500D01*
X266840Y28375D01*
X267027Y29250D01*
X267493Y30000D01*
X268333Y30500D01*
X269453Y30750D01*
X270107Y31250D01*
X270387Y32125D01*
X270200Y33000D01*
X269733Y33625D01*
X269080Y34000D01*
X268427D01*
X267773Y33750D01*
X267213Y33125D01*
G01X262513Y29000D02*
X260087D01*
G01X255573Y26500D02*
Y34000D01*
X252027D01*
G01X253333Y30375D02*
X255573D01*
G01X247420Y34000D02*
X245180D01*
G01X246300D02*
Y26500D01*
G01X247420D02*
X245180D01*
G01X238800Y34000D02*
Y26500D01*
G01X240947Y34000D02*
X236653D01*
G01X243012Y729449D02*
Y590473D01*
G01X319667Y600000D02*
Y607500D01*
X317427D01*
X316680Y607125D01*
X316120Y606250D01*
X315933Y605250D01*
X316120Y604250D01*
X316587Y603500D01*
X317427Y603125D01*
X319667D01*
G01X312167Y600000D02*
Y607500D01*
X309833D01*
X309087Y607125D01*
X308620Y606625D01*
X308433Y605625D01*
X308620Y604625D01*
X309180Y604000D01*
X309833Y603625D01*
X312167D01*
G01X309833D02*
X308433Y600000D01*
G01X300933D02*
X304667D01*
Y607500D01*
X300933D01*
G01X302427Y603875D02*
X304667D01*
G01X297260Y601000D02*
X296513Y600375D01*
X295673Y600000D01*
X294927D01*
X294180Y600375D01*
X293620Y601000D01*
X293340Y601875D01*
X293527Y602750D01*
X293993Y603500D01*
X294833Y604000D01*
X295953Y604250D01*
X296607Y604750D01*
X296887Y605625D01*
X296700Y606500D01*
X296233Y607125D01*
X295580Y607500D01*
X294927D01*
X294273Y607250D01*
X293713Y606625D01*
G01X289760Y601000D02*
X289013Y600375D01*
X288173Y600000D01*
X287427D01*
X286680Y600375D01*
X286120Y601000D01*
X285840Y601875D01*
X286027Y602750D01*
X286493Y603500D01*
X287333Y604000D01*
X288453Y604250D01*
X289107Y604750D01*
X289387Y605625D01*
X289200Y606500D01*
X288733Y607125D01*
X288080Y607500D01*
X287427D01*
X286773Y607250D01*
X286213Y606625D01*
G01X281513Y602500D02*
X279087D01*
G01X274573Y600000D02*
Y607500D01*
X271027D01*
G01X272333Y603875D02*
X274573D01*
G01X266420Y607500D02*
X264180D01*
G01X265300D02*
Y600000D01*
G01X266420D02*
X264180D01*
G01X257800Y607500D02*
Y600000D01*
G01X259947Y607500D02*
X255653D01*
G01X322540Y590473D02*
X228642D01*
G01D02*
Y729449D01*
G01X239983Y626557D02*
X240213Y626712D01*
X240481Y626815D01*
X240788D01*
X241133Y626660D01*
X241401Y626402D01*
X241593Y626092D01*
X241746Y625575D01*
X241784Y625110D01*
X241708Y624645D01*
X241593Y624335D01*
X241363Y624025D01*
X241094Y623818D01*
X240826Y623715D01*
X240558D01*
X240289Y623818D01*
X240059Y623973D01*
X239868Y624180D01*
G01X238569D02*
X238339Y623922D01*
X238071Y623767D01*
X237726Y623715D01*
X237381Y623818D01*
X237113Y624025D01*
X236921Y624387D01*
X236883Y624800D01*
X236959Y625213D01*
X237151Y625472D01*
X237419Y625678D01*
X237688Y625730D01*
X237956Y625678D01*
X238301Y625472D01*
X238186Y626815D01*
X237151D01*
G01X239983Y634431D02*
X240213Y634586D01*
X240481Y634689D01*
X240788D01*
X241133Y634534D01*
X241401Y634276D01*
X241593Y633966D01*
X241746Y633449D01*
X241784Y632984D01*
X241708Y632519D01*
X241593Y632209D01*
X241363Y631899D01*
X241094Y631692D01*
X240826Y631589D01*
X240558D01*
X240289Y631692D01*
X240059Y631847D01*
X239868Y632054D01*
G01X237266Y631589D02*
Y634689D01*
X238684Y632467D01*
X236768D01*
G01X239983Y618683D02*
X240213Y618838D01*
X240481Y618941D01*
X240788D01*
X241133Y618786D01*
X241401Y618528D01*
X241593Y618218D01*
X241746Y617701D01*
X241784Y617236D01*
X241708Y616771D01*
X241593Y616461D01*
X241363Y616151D01*
X241094Y615944D01*
X240826Y615841D01*
X240558D01*
X240289Y615944D01*
X240059Y616099D01*
X239868Y616306D01*
G01X238454Y617133D02*
X238186Y617494D01*
X237956Y617701D01*
X237649Y617804D01*
X237381Y617701D01*
X237189Y617494D01*
X237036Y617184D01*
X236998Y616823D01*
X237036Y616513D01*
X237189Y616203D01*
X237419Y615944D01*
X237688Y615841D01*
X237994Y615944D01*
X238263Y616254D01*
X238416Y616719D01*
X238454Y617236D01*
X238378Y617908D01*
X238263Y618269D01*
X238071Y618631D01*
X237803Y618889D01*
X237534Y618941D01*
X237266Y618838D01*
X237074Y618579D01*
G01X241669Y655211D02*
Y658311D01*
X240903D01*
X240596Y658156D01*
X240366Y657949D01*
X240174Y657639D01*
X240021Y657278D01*
X239983Y656761D01*
X240021Y656244D01*
X240174Y655883D01*
X240366Y655573D01*
X240596Y655366D01*
X240903Y655211D01*
X241669D01*
G01X238569Y655676D02*
X238339Y655418D01*
X238071Y655263D01*
X237726Y655211D01*
X237381Y655314D01*
X237113Y655521D01*
X236921Y655883D01*
X236883Y656296D01*
X236959Y656709D01*
X237151Y656968D01*
X237419Y657174D01*
X237688Y657226D01*
X237956Y657174D01*
X238301Y656968D01*
X238186Y658311D01*
X237151D01*
G01X241669Y647337D02*
Y650437D01*
X240903D01*
X240596Y650282D01*
X240366Y650075D01*
X240174Y649765D01*
X240021Y649404D01*
X239983Y648887D01*
X240021Y648370D01*
X240174Y648009D01*
X240366Y647699D01*
X240596Y647492D01*
X240903Y647337D01*
X241669D01*
G01X238454Y648629D02*
X238186Y648990D01*
X237956Y649197D01*
X237649Y649300D01*
X237381Y649197D01*
X237189Y648990D01*
X237036Y648680D01*
X236998Y648319D01*
X237036Y648009D01*
X237189Y647699D01*
X237419Y647440D01*
X237688Y647337D01*
X237994Y647440D01*
X238263Y647750D01*
X238416Y648215D01*
X238454Y648732D01*
X238378Y649404D01*
X238263Y649765D01*
X238071Y650127D01*
X237803Y650385D01*
X237534Y650437D01*
X237266Y650334D01*
X237074Y650075D01*
G01X241669Y663085D02*
Y666185D01*
X240903D01*
X240596Y666030D01*
X240366Y665823D01*
X240174Y665513D01*
X240021Y665152D01*
X239983Y664635D01*
X240021Y664118D01*
X240174Y663757D01*
X240366Y663447D01*
X240596Y663240D01*
X240903Y663085D01*
X241669D01*
G01X237266D02*
Y666185D01*
X238684Y663963D01*
X236768D01*
G01X228642Y729449D02*
X322540D01*
G01X262100Y-1054500D02*
X265900D01*
X262100Y-1062500D01*
X265900D01*
G01X272000Y-1057167D02*
Y-1062500D01*
G01Y-1055033D02*
X271800Y-1054900D01*
Y-1054633D01*
X272000Y-1054500D01*
X272200Y-1054633D01*
Y-1054900D01*
X272000Y-1055033D01*
G01X278700Y-1059833D02*
X281300D01*
G01X286200Y-1065167D02*
Y-1057167D01*
G01Y-1058367D02*
X286700Y-1057700D01*
X287200Y-1057300D01*
X288000Y-1057167D01*
X288700Y-1057300D01*
X289400Y-1057967D01*
X289700Y-1058900D01*
X289800Y-1059833D01*
X289700Y-1060767D01*
X289400Y-1061700D01*
X288800Y-1062233D01*
X288000Y-1062500D01*
X287300Y-1062367D01*
X286600Y-1061967D01*
X286200Y-1061434D01*
G01X296000Y-1057167D02*
Y-1062500D01*
G01Y-1055033D02*
X295800Y-1054900D01*
Y-1054633D01*
X296000Y-1054500D01*
X296200Y-1054633D01*
Y-1054900D01*
X296000Y-1055033D01*
G01X302300Y-1062500D02*
Y-1057167D01*
G01Y-1058500D02*
X302700Y-1057833D01*
X303300Y-1057300D01*
X304100Y-1057167D01*
X304800Y-1057300D01*
X305400Y-1057833D01*
X305700Y-1058767D01*
Y-1062500D01*
G01X310600Y-1064500D02*
X311300Y-1065033D01*
X312100Y-1065167D01*
X312800Y-1065033D01*
X313400Y-1064367D01*
X313800Y-1063433D01*
Y-1057167D01*
G01Y-1058233D02*
X313400Y-1057700D01*
X312800Y-1057300D01*
X312100Y-1057167D01*
X311300Y-1057433D01*
X310800Y-1057967D01*
X310400Y-1058900D01*
X310200Y-1059833D01*
X310300Y-1060633D01*
X310700Y-1061567D01*
X311300Y-1062233D01*
X312100Y-1062500D01*
X312700Y-1062367D01*
X313400Y-1061833D01*
X313800Y-1061300D01*
G01X311496Y616015D02*
X310538Y619115D01*
X309580Y616015D01*
G01X309925Y617100D02*
X311151D01*
G01X307438Y616015D02*
Y619115D01*
X307898Y618495D01*
G01Y616015D02*
X306978D01*
G01X311396Y623815D02*
X310438Y626915D01*
X309480Y623815D01*
G01X309825Y624900D02*
X311051D01*
G01X308066Y626398D02*
X307836Y626708D01*
X307568Y626863D01*
X307261Y626915D01*
X306878Y626812D01*
X306610Y626553D01*
X306533Y626243D01*
X306571Y625933D01*
X306725Y625675D01*
X307491Y625158D01*
X307836Y624797D01*
X308066Y624280D01*
X308143Y623815D01*
X306533D01*
G01X311396Y631689D02*
X310438Y634789D01*
X309480Y631689D01*
G01X309825Y632774D02*
X311051D01*
G01X308181Y632309D02*
X307951Y631947D01*
X307645Y631741D01*
X307300Y631689D01*
X306993Y631741D01*
X306686Y631999D01*
X306495Y632309D01*
X306456Y632619D01*
X306533Y632981D01*
X306801Y633239D01*
X307070Y633342D01*
X307415D01*
G01X307070D02*
X306840Y633497D01*
X306648Y633756D01*
X306571Y634066D01*
X306648Y634376D01*
X306840Y634634D01*
X307185Y634789D01*
X307530Y634737D01*
X307875Y634531D01*
G01X311166Y655311D02*
Y658411D01*
X309710D01*
G01X310246Y656913D02*
X311166D01*
G01X308066Y657894D02*
X307836Y658204D01*
X307568Y658359D01*
X307261Y658411D01*
X306878Y658308D01*
X306610Y658049D01*
X306533Y657739D01*
X306571Y657429D01*
X306725Y657171D01*
X307491Y656654D01*
X307836Y656293D01*
X308066Y655776D01*
X308143Y655311D01*
X306533D01*
G01X311166Y647437D02*
Y650537D01*
X309710D01*
G01X310246Y649039D02*
X311166D01*
G01X307338Y647437D02*
Y650537D01*
X307798Y649917D01*
G01Y647437D02*
X306878D01*
G01X311166Y663185D02*
Y666285D01*
X309710D01*
G01X310246Y664787D02*
X311166D01*
G01X308181Y663805D02*
X307951Y663443D01*
X307645Y663237D01*
X307300Y663185D01*
X306993Y663237D01*
X306686Y663495D01*
X306495Y663805D01*
X306456Y664115D01*
X306533Y664477D01*
X306801Y664735D01*
X307070Y664838D01*
X307415D01*
G01X307070D02*
X306840Y664993D01*
X306648Y665252D01*
X306571Y665562D01*
X306648Y665872D01*
X306840Y666130D01*
X307185Y666285D01*
X307530Y666233D01*
X307875Y666027D01*
G01X322540Y729449D02*
Y590473D01*
G01X369600Y-1055833D02*
X370200Y-1055033D01*
X370900Y-1054633D01*
X371700Y-1054500D01*
X372700Y-1054767D01*
X373400Y-1055433D01*
X373600Y-1056233D01*
X373500Y-1057034D01*
X373100Y-1057700D01*
X371100Y-1059033D01*
X370200Y-1059967D01*
X369600Y-1061300D01*
X369400Y-1062500D01*
X373600D01*
G01X379500Y-1054500D02*
X378700Y-1054767D01*
X378100Y-1055433D01*
X377700Y-1056233D01*
X377400Y-1057300D01*
X377300Y-1058500D01*
X377400Y-1059700D01*
X377700Y-1060767D01*
X378100Y-1061567D01*
X378700Y-1062233D01*
X379500Y-1062500D01*
X380300Y-1062233D01*
X380900Y-1061567D01*
X381300Y-1060767D01*
X381600Y-1059700D01*
X381700Y-1058500D01*
X381600Y-1057300D01*
X381300Y-1056233D01*
X380900Y-1055433D01*
X380300Y-1054767D01*
X379500Y-1054500D01*
G01X385600Y-1055833D02*
X386200Y-1055033D01*
X386900Y-1054633D01*
X387700Y-1054500D01*
X388700Y-1054767D01*
X389400Y-1055433D01*
X389600Y-1056233D01*
X389500Y-1057034D01*
X389100Y-1057700D01*
X387100Y-1059033D01*
X386200Y-1059967D01*
X385600Y-1061300D01*
X385400Y-1062500D01*
X389600D01*
G01X393600Y-1055833D02*
X394200Y-1055033D01*
X394900Y-1054633D01*
X395700Y-1054500D01*
X396700Y-1054767D01*
X397400Y-1055433D01*
X397600Y-1056233D01*
X397500Y-1057034D01*
X397100Y-1057700D01*
X395100Y-1059033D01*
X394200Y-1059967D01*
X393600Y-1061300D01*
X393400Y-1062500D01*
X397600D01*
G01X401700Y-1062767D02*
X405300Y-1054500D01*
G01X411500Y-1062500D02*
Y-1054500D01*
X410300Y-1056100D01*
G01Y-1062500D02*
X412700D01*
G01X417600Y-1055833D02*
X418200Y-1055033D01*
X418900Y-1054633D01*
X419700Y-1054500D01*
X420700Y-1054767D01*
X421400Y-1055433D01*
X421600Y-1056233D01*
X421500Y-1057034D01*
X421100Y-1057700D01*
X419100Y-1059033D01*
X418200Y-1059967D01*
X417600Y-1061300D01*
X417400Y-1062500D01*
X421600D01*
G01X425700Y-1062767D02*
X429300Y-1054500D01*
G01X435500Y-1062500D02*
Y-1054500D01*
X434300Y-1056100D01*
G01Y-1062500D02*
X436700D01*
G01X441300Y-1060900D02*
X441900Y-1061833D01*
X442700Y-1062367D01*
X443600Y-1062500D01*
X444400Y-1062367D01*
X445200Y-1061700D01*
X445700Y-1060900D01*
X445800Y-1060100D01*
X445600Y-1059167D01*
X444900Y-1058500D01*
X444200Y-1058233D01*
X443300D01*
G01X444200D02*
X444800Y-1057833D01*
X445300Y-1057167D01*
X445500Y-1056367D01*
X445300Y-1055567D01*
X444800Y-1054900D01*
X443900Y-1054500D01*
X443000Y-1054633D01*
X442100Y-1055167D01*
G01X369300Y-1040000D02*
Y-1032000D01*
X371300D01*
X372100Y-1032400D01*
X372700Y-1032933D01*
X373200Y-1033733D01*
X373600Y-1034667D01*
X373700Y-1036000D01*
X373600Y-1037333D01*
X373200Y-1038267D01*
X372700Y-1039067D01*
X372100Y-1039600D01*
X371300Y-1040000D01*
X369300D01*
G01X377000D02*
X379500Y-1032000D01*
X382000Y-1040000D01*
G01X381100Y-1037200D02*
X377900D01*
G01X385600Y-1040000D02*
Y-1032000D01*
X389400D01*
G01X388000Y-1035867D02*
X385600D01*
G01X395500Y-1032000D02*
X394700Y-1032267D01*
X394100Y-1032933D01*
X393700Y-1033733D01*
X393400Y-1034800D01*
X393300Y-1036000D01*
X393400Y-1037200D01*
X393700Y-1038267D01*
X394100Y-1039067D01*
X394700Y-1039733D01*
X395500Y-1040000D01*
X396300Y-1039733D01*
X396900Y-1039067D01*
X397300Y-1038267D01*
X397600Y-1037200D01*
X397700Y-1036000D01*
X397600Y-1034800D01*
X397300Y-1033733D01*
X396900Y-1032933D01*
X396300Y-1032267D01*
X395500Y-1032000D01*
G01X403500D02*
Y-1040000D01*
G01X401200Y-1032000D02*
X405800D01*
G01X409500Y-1040000D02*
Y-1032000D01*
X411900D01*
X412700Y-1032400D01*
X413300Y-1033333D01*
X413500Y-1034400D01*
X413300Y-1035467D01*
X412800Y-1036267D01*
X411900Y-1036667D01*
X409500D01*
G01X420300Y-1035733D02*
X420700Y-1035333D01*
X421000Y-1034667D01*
X421200Y-1033733D01*
X421000Y-1032933D01*
X420600Y-1032400D01*
X419900Y-1032000D01*
X417200D01*
Y-1040000D01*
X420500D01*
X421200Y-1039467D01*
X421600Y-1038667D01*
X421800Y-1037733D01*
X421600Y-1036800D01*
X421000Y-1036000D01*
X420300Y-1035733D01*
X417200D01*
G01X427500Y-1040000D02*
Y-1032000D01*
X426300Y-1033600D01*
G01Y-1040000D02*
X428700D01*
G01X433000D02*
X435500Y-1032000D01*
X438000Y-1040000D01*
G01X437100Y-1037200D02*
X433900D01*
G01X441600Y-1040000D02*
Y-1032000D01*
X445400D01*
G01X444000Y-1035867D02*
X441600D01*
G01X451500Y-1032000D02*
X450700Y-1032267D01*
X450100Y-1032933D01*
X449700Y-1033733D01*
X449400Y-1034800D01*
X449300Y-1036000D01*
X449400Y-1037200D01*
X449700Y-1038267D01*
X450100Y-1039067D01*
X450700Y-1039733D01*
X451500Y-1040000D01*
X452300Y-1039733D01*
X452900Y-1039067D01*
X453300Y-1038267D01*
X453600Y-1037200D01*
X453700Y-1036000D01*
X453600Y-1034800D01*
X453300Y-1033733D01*
X452900Y-1032933D01*
X452300Y-1032267D01*
X451500Y-1032000D01*
G01X389600Y-1012500D02*
Y-1004500D01*
X393400D01*
G01X392000Y-1008367D02*
X389600D01*
G01X399500Y-1004500D02*
X398700Y-1004767D01*
X398100Y-1005433D01*
X397700Y-1006233D01*
X397400Y-1007300D01*
X397300Y-1008500D01*
X397400Y-1009700D01*
X397700Y-1010767D01*
X398100Y-1011567D01*
X398700Y-1012233D01*
X399500Y-1012500D01*
X400300Y-1012233D01*
X400900Y-1011567D01*
X401300Y-1010767D01*
X401600Y-1009700D01*
X401700Y-1008500D01*
X401600Y-1007300D01*
X401300Y-1006233D01*
X400900Y-1005433D01*
X400300Y-1004767D01*
X399500Y-1004500D01*
G01X407500D02*
Y-1012500D01*
G01X405200Y-1004500D02*
X409800D01*
G01X412500Y-1015167D02*
X418500D01*
G01X421500Y-1012500D02*
Y-1004500D01*
X423900D01*
X424700Y-1004900D01*
X425300Y-1005833D01*
X425500Y-1006900D01*
X425300Y-1007967D01*
X424800Y-1008767D01*
X423900Y-1009167D01*
X421500D01*
G01X429300Y-1012500D02*
Y-1004500D01*
X431300D01*
X432100Y-1004900D01*
X432700Y-1005433D01*
X433200Y-1006233D01*
X433600Y-1007167D01*
X433700Y-1008500D01*
X433600Y-1009833D01*
X433200Y-1010767D01*
X432700Y-1011567D01*
X432100Y-1012100D01*
X431300Y-1012500D01*
X429300D01*
G01X440300Y-1008233D02*
X440700Y-1007833D01*
X441000Y-1007167D01*
X441200Y-1006233D01*
X441000Y-1005433D01*
X440600Y-1004900D01*
X439900Y-1004500D01*
X437200D01*
Y-1012500D01*
X440500D01*
X441200Y-1011967D01*
X441600Y-1011167D01*
X441800Y-1010233D01*
X441600Y-1009300D01*
X441000Y-1008500D01*
X440300Y-1008233D01*
X437200D01*
G01X444500Y-1015167D02*
X450500D01*
G01X456300Y-1008233D02*
X456700Y-1007833D01*
X457000Y-1007167D01*
X457200Y-1006233D01*
X457000Y-1005433D01*
X456600Y-1004900D01*
X455900Y-1004500D01*
X453200D01*
Y-1012500D01*
X456500D01*
X457200Y-1011967D01*
X457600Y-1011167D01*
X457800Y-1010233D01*
X457600Y-1009300D01*
X457000Y-1008500D01*
X456300Y-1008233D01*
X453200D01*
G01X461300Y-1012500D02*
Y-1004500D01*
X463300D01*
X464100Y-1004900D01*
X464700Y-1005433D01*
X465200Y-1006233D01*
X465600Y-1007167D01*
X465700Y-1008500D01*
X465600Y-1009833D01*
X465200Y-1010767D01*
X464700Y-1011567D01*
X464100Y-1012100D01*
X463300Y-1012500D01*
X461300D01*
G01X468500Y-1015167D02*
X474500D01*
G01X480100Y-1008500D02*
X482100D01*
Y-1010900D01*
X481500Y-1011700D01*
X480800Y-1012233D01*
X479800Y-1012500D01*
X478800Y-1012233D01*
X478100Y-1011700D01*
X477500Y-1010900D01*
X477100Y-1009967D01*
X476900Y-1008900D01*
Y-1007967D01*
X477100Y-1007167D01*
X477500Y-1006233D01*
X478100Y-1005433D01*
X478700Y-1004900D01*
X479500Y-1004500D01*
X480200D01*
X481000Y-1004767D01*
X481600Y-1005300D01*
G01X485500Y-1012500D02*
Y-1004500D01*
X487900D01*
X488700Y-1004900D01*
X489300Y-1005833D01*
X489500Y-1006900D01*
X489300Y-1007967D01*
X488800Y-1008767D01*
X487900Y-1009167D01*
X485500D01*
G01X493300Y-1004500D02*
Y-1010233D01*
X493700Y-1011434D01*
X494500Y-1012233D01*
X495500Y-1012500D01*
X496500Y-1012233D01*
X497300Y-1011434D01*
X497700Y-1010233D01*
Y-1004500D01*
G01X414600Y171800D02*
X404400D01*
Y167200D01*
X414600D01*
Y171800D01*
G01Y216300D02*
X404400D01*
Y211700D01*
X414600D01*
Y216300D01*
G01X414700Y167100D02*
Y156900D01*
X419300D01*
Y167100D01*
X414700D01*
G01X413000Y177800D02*
X423200D01*
Y182400D01*
X413000D01*
Y177800D01*
G01X439700Y171500D02*
Y177700D01*
X436500D01*
Y171500D01*
X439700D01*
G01X432500Y177700D02*
Y171500D01*
X435700D01*
Y177700D01*
X432500D01*
G01X419800Y167400D02*
Y177600D01*
X415200D01*
Y167400D01*
X419800D01*
G01X428000Y162873D02*
Y165113D01*
G01X429625Y163900D02*
X426375D01*
G01X431417Y157950D02*
Y161050D01*
X430497D01*
X430190Y160895D01*
X429960Y160533D01*
X429883Y160120D01*
X429960Y159707D01*
X430152Y159397D01*
X430497Y159242D01*
X431417D01*
G01X428393Y157950D02*
Y161050D01*
X427627D01*
X427320Y160895D01*
X427090Y160688D01*
X426898Y160378D01*
X426745Y160017D01*
X426707Y159500D01*
X426745Y158983D01*
X426898Y158622D01*
X427090Y158312D01*
X427320Y158105D01*
X427627Y157950D01*
X428393D01*
G01X424450D02*
Y161050D01*
X424910Y160430D01*
G01Y157950D02*
X423990D01*
G01X421350D02*
X421082Y158002D01*
X420775Y158157D01*
X420583Y158415D01*
X420507Y158777D01*
X420583Y159138D01*
X420813Y159448D01*
X421158Y159603D01*
X421542D01*
X421772Y159707D01*
X421963Y159965D01*
X422040Y160327D01*
X421925Y160688D01*
X421657Y160947D01*
X421350Y161050D01*
X421043Y160947D01*
X420775Y160688D01*
X420660Y160327D01*
X420737Y159965D01*
X420928Y159707D01*
X421158Y159603D01*
X421542D01*
X421887Y159448D01*
X422117Y159138D01*
X422193Y158777D01*
X422117Y158415D01*
X421925Y158157D01*
X421618Y158002D01*
X421350Y157950D01*
G01X430900Y168100D02*
Y182600D01*
X425300D01*
Y168100D01*
X430900D01*
G01X430069Y173419D02*
X426131D01*
X428100Y175387D01*
X430069Y173419D01*
G01Y175781D02*
X426131D01*
G01X420400Y174600D02*
Y168400D01*
X423600D01*
Y174600D01*
X420400D01*
G01X415200Y211100D02*
Y200900D01*
X419800D01*
Y211100D01*
X415200D01*
G01X427300Y209373D02*
Y211613D01*
G01X428925Y210400D02*
X425675D01*
G01X431917Y203950D02*
Y207050D01*
X430997D01*
X430690Y206895D01*
X430460Y206533D01*
X430383Y206120D01*
X430460Y205707D01*
X430652Y205397D01*
X430997Y205242D01*
X431917D01*
G01X428893Y203950D02*
Y207050D01*
X428127D01*
X427820Y206895D01*
X427590Y206688D01*
X427398Y206378D01*
X427245Y206017D01*
X427207Y205500D01*
X427245Y204983D01*
X427398Y204622D01*
X427590Y204312D01*
X427820Y204105D01*
X428127Y203950D01*
X428893D01*
G01X424950D02*
Y207050D01*
X425410Y206430D01*
G01Y203950D02*
X424490D01*
G01X421927D02*
X421850Y204622D01*
X421735Y205190D01*
X421582Y205707D01*
X421390Y206275D01*
X421083Y207050D01*
X422617D01*
G01X428200Y183387D02*
Y185813D01*
G01X430800Y182100D02*
X425400D01*
G01Y181600D02*
X430800D01*
G01Y181100D02*
X425400D01*
G01X413000Y222200D02*
X423200D01*
Y226800D01*
X413000D01*
Y222200D01*
G01X432500Y222100D02*
Y215900D01*
X435700D01*
Y222100D01*
X432500D01*
G01X436500D02*
Y215900D01*
X439700D01*
Y222100D01*
X436500D01*
G01X419800Y211400D02*
Y221600D01*
X415200D01*
Y211400D01*
X419800D01*
G01X428200Y227787D02*
Y230213D01*
G01X430800Y226500D02*
X425400D01*
G01Y226000D02*
X430800D01*
G01Y225500D02*
X425400D01*
G01X430900Y212500D02*
Y227000D01*
X425300D01*
Y212500D01*
X430900D01*
G01X430069Y217819D02*
X426131D01*
X428100Y219787D01*
X430069Y217819D01*
G01Y220181D02*
X426131D01*
G01X420400Y219100D02*
Y212900D01*
X423600D01*
Y219100D01*
X420400D01*
G01X458000Y-1065500D02*
Y-1057500D01*
X456800Y-1059100D01*
G01Y-1065500D02*
X459200D01*
G01X464100Y-1062167D02*
X464800Y-1061233D01*
X465400Y-1060700D01*
X466200Y-1060433D01*
X466900Y-1060700D01*
X467400Y-1061233D01*
X467800Y-1062033D01*
X467900Y-1062967D01*
X467800Y-1063767D01*
X467400Y-1064567D01*
X466800Y-1065233D01*
X466100Y-1065500D01*
X465300Y-1065233D01*
X464600Y-1064434D01*
X464200Y-1063233D01*
X464100Y-1061900D01*
X464300Y-1060167D01*
X464600Y-1059233D01*
X465100Y-1058300D01*
X465800Y-1057633D01*
X466500Y-1057500D01*
X467200Y-1057767D01*
X467700Y-1058433D01*
G01X474000Y-1065767D02*
X473800Y-1065633D01*
Y-1065367D01*
X474000Y-1065233D01*
X474200Y-1065367D01*
Y-1065633D01*
X474000Y-1065767D01*
G01X480100Y-1062167D02*
X480800Y-1061233D01*
X481400Y-1060700D01*
X482200Y-1060433D01*
X482900Y-1060700D01*
X483400Y-1061233D01*
X483800Y-1062033D01*
X483900Y-1062967D01*
X483800Y-1063767D01*
X483400Y-1064567D01*
X482800Y-1065233D01*
X482100Y-1065500D01*
X481300Y-1065233D01*
X480600Y-1064434D01*
X480200Y-1063233D01*
X480100Y-1061900D01*
X480300Y-1060167D01*
X480600Y-1059233D01*
X481100Y-1058300D01*
X481800Y-1057633D01*
X482500Y-1057500D01*
X483200Y-1057767D01*
X483700Y-1058433D01*
G01X503000Y-1065500D02*
Y-1057500D01*
X501800Y-1059100D01*
G01Y-1065500D02*
X504200D01*
G01X510800D02*
X511000Y-1063767D01*
X511300Y-1062300D01*
X511700Y-1060967D01*
X512200Y-1059500D01*
X513000Y-1057500D01*
X509000D01*
G01X519000Y-1065767D02*
X518800Y-1065633D01*
Y-1065367D01*
X519000Y-1065233D01*
X519200Y-1065367D01*
Y-1065633D01*
X519000Y-1065767D01*
G01X525100Y-1058833D02*
X525700Y-1058033D01*
X526400Y-1057633D01*
X527200Y-1057500D01*
X528200Y-1057767D01*
X528900Y-1058433D01*
X529100Y-1059233D01*
X529000Y-1060034D01*
X528600Y-1060700D01*
X526600Y-1062033D01*
X525700Y-1062967D01*
X525100Y-1064300D01*
X524900Y-1065500D01*
X529100D01*
G01X523100Y-1040500D02*
Y-1032500D01*
X526900D01*
G01X525500Y-1036367D02*
X523100D01*
G01X591100Y238300D02*
Y231700D01*
X604100D01*
Y238300D01*
X591100D01*
G01X608117Y227000D02*
Y230100D01*
X607197D01*
X606890Y229945D01*
X606660Y229583D01*
X606583Y229170D01*
X606660Y228757D01*
X606852Y228447D01*
X607197Y228292D01*
X608117D01*
G01X605017Y227620D02*
X604825Y227310D01*
X604595Y227103D01*
X604327Y227000D01*
X604020Y227103D01*
X603790Y227310D01*
X603560Y227620D01*
X603483Y228033D01*
Y230100D01*
G01X601993Y227465D02*
X601763Y227207D01*
X601495Y227052D01*
X601150Y227000D01*
X600805Y227103D01*
X600537Y227310D01*
X600345Y227672D01*
X600307Y228085D01*
X600383Y228498D01*
X600575Y228757D01*
X600843Y228963D01*
X601112Y229015D01*
X601380Y228963D01*
X601725Y228757D01*
X601610Y230100D01*
X600575D01*
G01X591300Y241000D02*
X597900D01*
Y254000D01*
X591300D01*
Y241000D01*
G01X603084Y243900D02*
X609284D01*
Y247100D01*
X603084D01*
Y243900D01*
G01X606084Y254100D02*
Y247900D01*
X609284D01*
Y254100D01*
X606084D01*
G01X620617Y256500D02*
Y259600D01*
X619697D01*
X619390Y259445D01*
X619160Y259083D01*
X619083Y258670D01*
X619160Y258257D01*
X619352Y257947D01*
X619697Y257792D01*
X620617D01*
G01X617593Y259600D02*
Y257378D01*
X617440Y256913D01*
X617133Y256603D01*
X616750Y256500D01*
X616367Y256603D01*
X616060Y256913D01*
X615907Y257378D01*
Y259600D01*
G01X613650Y256500D02*
X613382Y256552D01*
X613075Y256707D01*
X612883Y256965D01*
X612807Y257327D01*
X612883Y257688D01*
X613113Y257998D01*
X613458Y258153D01*
X613842D01*
X614072Y258257D01*
X614263Y258515D01*
X614340Y258877D01*
X614225Y259238D01*
X613957Y259497D01*
X613650Y259600D01*
X613343Y259497D01*
X613075Y259238D01*
X612960Y258877D01*
X613037Y258515D01*
X613228Y258257D01*
X613458Y258153D01*
X613842D01*
X614187Y257998D01*
X614417Y257688D01*
X614493Y257327D01*
X614417Y256965D01*
X614225Y256707D01*
X613918Y256552D01*
X613650Y256500D01*
G01X618584Y262024D02*
X620660D01*
G01X592708Y264100D02*
Y262024D01*
X594784D01*
G01X596984D02*
X602624D01*
G01X620660Y287900D02*
Y289976D01*
X618584D01*
G01X602624D02*
X596984D01*
G01X594784D02*
X592708D01*
Y287900D01*
G01Y275900D02*
Y270200D01*
G01X609384Y308800D02*
Y316200D01*
X591984D01*
Y308800D01*
X609384D01*
G01X611084Y307100D02*
Y300900D01*
X614284D01*
Y307100D01*
X611084D01*
G01X615084D02*
Y300900D01*
X618284D01*
Y307100D01*
X615084D01*
G01X614284Y309400D02*
Y315600D01*
X611084D01*
Y309400D01*
X614284D01*
G01X618284D02*
Y315600D01*
X615084D01*
Y309400D01*
X618284D01*
G01X603584Y300900D02*
X609784D01*
Y304100D01*
X603584D01*
Y300900D01*
G01X628684Y239800D02*
X625782Y236898D01*
X619826D01*
Y249102D01*
X637542D01*
Y236898D01*
X631586D01*
X628684Y239800D01*
G01X620484Y234700D02*
Y227300D01*
X637884D01*
Y234700D01*
X620484D01*
G01X639784Y270600D02*
X633584D01*
Y267400D01*
X639784D01*
Y270600D01*
G01Y266100D02*
X633584D01*
Y262900D01*
X639784D01*
Y266100D01*
G01Y261600D02*
X633584D01*
Y258400D01*
X639784D01*
Y261600D01*
G01X620660Y262024D02*
Y264100D01*
G01X636693Y254100D02*
Y251878D01*
X636540Y251413D01*
X636233Y251103D01*
X635850Y251000D01*
X635467Y251103D01*
X635160Y251413D01*
X635007Y251878D01*
Y254100D01*
G01X633593Y251620D02*
X633363Y251258D01*
X633057Y251052D01*
X632712Y251000D01*
X632405Y251052D01*
X632098Y251310D01*
X631907Y251620D01*
X631868Y251930D01*
X631945Y252292D01*
X632213Y252550D01*
X632482Y252653D01*
X632827D01*
G01X632482D02*
X632252Y252808D01*
X632060Y253067D01*
X631983Y253377D01*
X632060Y253687D01*
X632252Y253945D01*
X632597Y254100D01*
X632942Y254048D01*
X633287Y253842D01*
G01X630378Y253583D02*
X630148Y253893D01*
X629880Y254048D01*
X629573Y254100D01*
X629190Y253997D01*
X628922Y253738D01*
X628845Y253428D01*
X628883Y253118D01*
X629037Y252860D01*
X629803Y252343D01*
X630148Y251982D01*
X630378Y251465D01*
X630455Y251000D01*
X628845D01*
G01X633584Y282100D02*
Y275900D01*
X636784D01*
Y282100D01*
X633584D01*
G01X637584Y275900D02*
X643784D01*
Y279100D01*
X637584D01*
Y275900D01*
G01X636784Y291900D02*
Y298100D01*
X633584D01*
Y291900D01*
X636784D01*
G01X639784Y275100D02*
X633584D01*
Y271900D01*
X639784D01*
Y275100D01*
G01Y290100D02*
X633584D01*
Y286900D01*
X639784D01*
Y290100D01*
G01X626584Y280400D02*
X632784D01*
Y283600D01*
X626584D01*
Y280400D01*
G01X633584Y282900D02*
X639784D01*
Y286100D01*
X633584D01*
Y282900D01*
G01X638084Y296400D02*
X644284D01*
Y299600D01*
X638084D01*
Y296400D01*
G01Y291900D02*
X644284D01*
Y295100D01*
X638084D01*
Y291900D01*
G01Y301200D02*
X648284D01*
Y305800D01*
X638084D01*
Y301200D01*
G01X640000Y306900D02*
X646200D01*
Y310100D01*
X640000D01*
Y306900D01*
G01X636784Y299900D02*
Y306100D01*
X633584D01*
Y299900D01*
X636784D01*
G01X623784Y300900D02*
Y307100D01*
X620584D01*
Y300900D01*
X623784D01*
G01X654684Y236800D02*
Y230200D01*
X667684D01*
Y236800D01*
X654684D01*
G01X662384Y214000D02*
X668984D01*
Y227000D01*
X662384D01*
Y214000D01*
G01X670384D02*
X676984D01*
Y227000D01*
X670384D01*
Y214000D01*
G01X678384D02*
X684984D01*
Y227000D01*
X678384D01*
Y214000D01*
G01X667784Y264100D02*
X661584D01*
Y260900D01*
X667784D01*
Y264100D01*
G01X678500Y254100D02*
Y247900D01*
X681700D01*
Y254100D01*
X678500D01*
G01X667784Y256100D02*
X661584D01*
Y252900D01*
X667784D01*
Y256100D01*
G01X667084Y267400D02*
X673284D01*
Y270600D01*
X667084D01*
Y267400D01*
G01X665784Y268600D02*
X659584D01*
Y265400D01*
X665784D01*
Y268600D01*
G01X674500Y254100D02*
Y247900D01*
X677700D01*
Y254100D01*
X674500D01*
G01X670584D02*
Y247900D01*
X673784D01*
Y254100D01*
X670584D01*
G01X667784Y260100D02*
X661584D01*
Y256900D01*
X667784D01*
Y260100D01*
G01X673284Y276300D02*
X663084D01*
Y271700D01*
X673284D01*
Y276300D01*
G01X663084Y290900D02*
X669284D01*
Y294100D01*
X663084D01*
Y290900D01*
G01Y294900D02*
X669284D01*
Y298100D01*
X663084D01*
Y294900D01*
G01Y278900D02*
X669284D01*
Y282100D01*
X663084D01*
Y278900D01*
G01X669200Y302100D02*
X663000D01*
Y298900D01*
X669200D01*
Y302100D01*
G01X663084Y282900D02*
X669284D01*
Y286100D01*
X663084D01*
Y282900D01*
G01Y286900D02*
X669284D01*
Y290100D01*
X663084D01*
Y286900D01*
G01X669200Y306100D02*
X663000D01*
Y302900D01*
X669200D01*
Y306100D01*
G01X663000Y306900D02*
X669200D01*
Y310100D01*
X663000D01*
Y306900D01*
G01X687204Y585074D02*
Y611300D01*
X652628Y598187D01*
X687204Y585074D01*
G01X712200Y205300D02*
X702000D01*
Y200700D01*
X712200D01*
Y205300D01*
G01X705300Y186500D02*
X711900D01*
Y199500D01*
X705300D01*
Y186500D01*
G01X712100Y209600D02*
X705900D01*
Y206400D01*
X712100D01*
Y209600D01*
G01X710250Y219701D02*
Y237299D01*
X702950D01*
Y219701D01*
X710250D01*
G01X686384Y214000D02*
X692984D01*
Y227000D01*
X686384D01*
Y214000D01*
G01X705900Y210400D02*
X712100D01*
Y213600D01*
X705900D01*
Y210400D01*
G01X710300Y238300D02*
Y245700D01*
X692900D01*
Y238300D01*
X710300D01*
G01X686584Y254100D02*
Y247900D01*
X689784D01*
Y254100D01*
X686584D01*
G01X682584D02*
Y247900D01*
X685784D01*
Y254100D01*
X682584D01*
G01X698084D02*
Y247900D01*
X701284D01*
Y254100D01*
X698084D01*
G01X690584Y249400D02*
X696784D01*
Y252600D01*
X690584D01*
Y249400D01*
G01X712867Y255950D02*
Y259050D01*
X711947D01*
X711640Y258895D01*
X711410Y258533D01*
X711333Y258120D01*
X711410Y257707D01*
X711602Y257397D01*
X711947Y257242D01*
X712867D01*
G01X709843Y259050D02*
Y256828D01*
X709690Y256363D01*
X709383Y256053D01*
X709000Y255950D01*
X708617Y256053D01*
X708310Y256363D01*
X708157Y256828D01*
Y259050D01*
G01X706552Y256312D02*
X706283Y256053D01*
X705977Y255950D01*
X705670Y256053D01*
X705402Y256363D01*
X705210Y256828D01*
X705133Y257293D01*
Y257862D01*
X705210Y258327D01*
X705402Y258740D01*
X705632Y258947D01*
X705900Y259050D01*
X706207Y258947D01*
X706437Y258740D01*
X706590Y258430D01*
X706667Y258017D01*
X706590Y257655D01*
X706398Y257293D01*
X706168Y257087D01*
X705900Y257035D01*
X705593Y257138D01*
X705363Y257397D01*
X705133Y257862D01*
G01X684884Y264024D02*
X682739D01*
Y266100D01*
G01X702584Y264024D02*
X698784D01*
G01Y291976D02*
X702584D01*
G01X682739Y289900D02*
Y291976D01*
G01D02*
X684884D01*
G01X703684Y308000D02*
Y302000D01*
X715684D01*
Y308000D01*
X703684D01*
G01X693484Y323000D02*
X686884D01*
Y310000D01*
X693484D01*
Y323000D01*
G01X702484D02*
X695884D01*
Y310000D01*
X702484D01*
Y323000D01*
G01X696084Y304900D02*
X702284D01*
Y308100D01*
X696084D01*
Y304900D01*
G01X691584Y300400D02*
X697784D01*
Y303600D01*
X691584D01*
Y300400D01*
G01X693284Y308100D02*
X687084D01*
Y304900D01*
X693284D01*
Y308100D01*
G01X689507Y584770D02*
X689197Y584962D01*
X688990Y585192D01*
X688887Y585460D01*
X688990Y585767D01*
X689197Y585997D01*
X689507Y586227D01*
X689920Y586304D01*
X691987D01*
G01X688887Y588637D02*
X691987D01*
X691367Y588177D01*
G01X688887D02*
Y589097D01*
G01X689507Y590894D02*
X689145Y591124D01*
X688939Y591430D01*
X688887Y591775D01*
X688939Y592082D01*
X689197Y592389D01*
X689507Y592580D01*
X689817Y592619D01*
X690179Y592542D01*
X690437Y592274D01*
X690540Y592005D01*
Y591660D01*
G01Y592005D02*
X690695Y592235D01*
X690954Y592427D01*
X691264Y592504D01*
X691574Y592427D01*
X691832Y592235D01*
X691987Y591890D01*
X691935Y591545D01*
X691729Y591200D01*
G01X732350Y183806D02*
X746850D01*
Y133194D01*
X732350D01*
Y183806D01*
G01X726000Y178087D02*
Y180513D01*
G01X740356Y187081D02*
X756800D01*
G01X740356Y187281D02*
X764844D01*
G01X740356Y187481D02*
X764844D01*
G01X740356Y187881D02*
X764844D01*
G01X740356Y188281D02*
X764844D01*
G01X740356Y188581D02*
X764844D01*
G01X740356Y189850D02*
Y191137D01*
G01Y190237D02*
Y191437D01*
G01Y189475D02*
X764844D01*
G01X740356D02*
X764844D01*
G01X740356Y191531D02*
Y189124D01*
G01Y189514D02*
X764844D01*
G01X740356Y189475D02*
X764844D01*
G01X740356Y189081D02*
X764844D01*
G01Y189224D02*
Y226364D01*
X740356D01*
Y189324D01*
G01X756800Y186700D02*
X740356D01*
Y189169D01*
G01X713856Y187081D02*
X738344D01*
G01X713856Y187281D02*
X738344D01*
G01X713856Y187481D02*
X738344D01*
G01X713856Y187881D02*
X738344D01*
G01X713856Y188281D02*
X738344D01*
G01X713856Y188581D02*
X738344D01*
G01X713856Y189850D02*
Y191137D01*
G01X738344Y189324D02*
Y186700D01*
X721900D01*
G01X713856Y190237D02*
Y191437D01*
G01Y189475D02*
X738344D01*
G01Y189124D02*
Y194004D01*
G01Y189324D02*
Y189850D01*
G01X713856Y189475D02*
X738344D01*
G01X713856Y191531D02*
Y189124D01*
G01X738344Y191637D02*
Y191531D01*
G01X713856Y189514D02*
X738344D01*
G01X713856Y189475D02*
X738344D01*
G01X713856Y189081D02*
X738344D01*
G01X738051Y189437D02*
X737851Y189450D01*
G01X738344Y189224D02*
Y226364D01*
X713856D01*
Y189324D01*
G01X730100Y210000D02*
X722100D01*
X726100Y205000D01*
X730100Y210000D01*
G01X731100Y205000D02*
X721100D01*
G01X726100D02*
Y203200D01*
G01X718500Y186700D02*
X713856D01*
Y189169D01*
G01X726700Y233373D02*
Y235613D01*
G01X728325Y234400D02*
X725075D01*
G01X736117Y237500D02*
Y240600D01*
X735197D01*
X734890Y240445D01*
X734660Y240083D01*
X734583Y239670D01*
X734660Y239257D01*
X734852Y238947D01*
X735197Y238792D01*
X736117D01*
G01X733093Y237500D02*
Y240600D01*
X732327D01*
X732020Y240445D01*
X731790Y240238D01*
X731598Y239928D01*
X731445Y239567D01*
X731407Y239050D01*
X731445Y238533D01*
X731598Y238172D01*
X731790Y237862D01*
X732020Y237655D01*
X732327Y237500D01*
X733093D01*
G01X729150D02*
Y240600D01*
X729610Y239980D01*
G01Y237500D02*
X728690D01*
G01X726778Y240083D02*
X726548Y240393D01*
X726280Y240548D01*
X725973Y240600D01*
X725590Y240497D01*
X725322Y240238D01*
X725245Y239928D01*
X725283Y239618D01*
X725437Y239360D01*
X726203Y238843D01*
X726548Y238482D01*
X726778Y237965D01*
X726855Y237500D01*
X725245D01*
G01X726100Y212200D02*
Y210400D01*
G01X714629Y266100D02*
Y264024D01*
X712484D01*
G01X732884Y288700D02*
X725484D01*
Y271300D01*
X732884D01*
Y288700D01*
G01X712484Y291976D02*
X714629D01*
Y289900D01*
G01X730684Y301700D02*
Y308300D01*
X717684D01*
Y301700D01*
X730684D01*
G01X847559Y65689D02*
X766536D01*
Y336279D01*
X847559D01*
Y65689D01*
G01X750000Y133422D02*
X753100D01*
Y134878D01*
G01X751602Y134342D02*
Y133422D01*
G01X750413Y136445D02*
X750155Y136752D01*
X750000Y137097D01*
Y137403D01*
X750155Y137710D01*
X750413Y137940D01*
X750775Y138055D01*
X751137Y137978D01*
X751447Y137787D01*
X751653Y137442D01*
X751757Y136982D01*
X751963Y136713D01*
X752325Y136598D01*
X752687Y136675D01*
X752945Y136867D01*
X753100Y137135D01*
Y137403D01*
X752997Y137672D01*
X752738Y137902D01*
G01X751292Y139622D02*
X751653Y139890D01*
X751860Y140120D01*
X751963Y140427D01*
X751860Y140695D01*
X751653Y140887D01*
X751343Y141040D01*
X750982Y141078D01*
X750672Y141040D01*
X750362Y140887D01*
X750103Y140657D01*
X750000Y140388D01*
X750103Y140082D01*
X750413Y139813D01*
X750878Y139660D01*
X751395Y139622D01*
X752067Y139698D01*
X752428Y139813D01*
X752790Y140005D01*
X753048Y140273D01*
X753100Y140542D01*
X752997Y140810D01*
X752738Y141002D01*
G01X768100Y171633D02*
X775600D01*
Y173873D01*
X775225Y174620D01*
X774350Y175180D01*
X773350Y175367D01*
X772350Y175180D01*
X771600Y174713D01*
X771225Y173873D01*
Y171633D01*
G01X768100Y179133D02*
X775600D01*
Y181467D01*
X775225Y182213D01*
X774725Y182680D01*
X773725Y182867D01*
X772725Y182680D01*
X772100Y182120D01*
X771725Y181467D01*
Y179133D01*
G01Y181467D02*
X768100Y182867D01*
G01Y190367D02*
Y186633D01*
X775600D01*
Y190367D01*
G01X771975Y188873D02*
Y186633D01*
G01X769100Y194040D02*
X768475Y194787D01*
X768100Y195627D01*
Y196373D01*
X768475Y197120D01*
X769100Y197680D01*
X769975Y197960D01*
X770850Y197773D01*
X771600Y197307D01*
X772100Y196467D01*
X772350Y195347D01*
X772850Y194693D01*
X773725Y194413D01*
X774600Y194600D01*
X775225Y195067D01*
X775600Y195720D01*
Y196373D01*
X775350Y197027D01*
X774725Y197587D01*
G01X769100Y201540D02*
X768475Y202287D01*
X768100Y203127D01*
Y203873D01*
X768475Y204620D01*
X769100Y205180D01*
X769975Y205460D01*
X770850Y205273D01*
X771600Y204807D01*
X772100Y203967D01*
X772350Y202847D01*
X772850Y202193D01*
X773725Y201913D01*
X774600Y202100D01*
X775225Y202567D01*
X775600Y203220D01*
Y203873D01*
X775350Y204527D01*
X774725Y205087D01*
G01X770600Y209787D02*
Y212213D01*
G01X768100Y216727D02*
X775600D01*
Y220273D01*
G01X771975Y218967D02*
Y216727D01*
G01X775600Y224880D02*
Y227120D01*
G01Y226000D02*
X768100D01*
G01Y224880D02*
Y227120D01*
G01X775600Y233500D02*
X768100D01*
G01X775600Y231353D02*
Y235647D01*
G01X753000Y180087D02*
Y182513D01*
G01X764844Y189324D02*
Y186700D01*
X760500D01*
G01X764844Y189124D02*
Y194004D01*
G01Y189324D02*
Y189850D01*
G01Y191637D02*
Y191531D01*
G01X764551Y189437D02*
X764351Y189450D01*
G01X756600Y210000D02*
X748600D01*
X752600Y205000D01*
X756600Y210000D01*
G01X757600Y205000D02*
X747600D01*
G01X752600D02*
Y203200D01*
G01X760500Y187081D02*
X764844D01*
G01X753200Y233373D02*
Y235613D01*
G01X754825Y234400D02*
X751575D01*
G01X762117Y237500D02*
Y240600D01*
X761197D01*
X760890Y240445D01*
X760660Y240083D01*
X760583Y239670D01*
X760660Y239257D01*
X760852Y238947D01*
X761197Y238792D01*
X762117D01*
G01X759093Y237500D02*
Y240600D01*
X758327D01*
X758020Y240445D01*
X757790Y240238D01*
X757598Y239928D01*
X757445Y239567D01*
X757407Y239050D01*
X757445Y238533D01*
X757598Y238172D01*
X757790Y237862D01*
X758020Y237655D01*
X758327Y237500D01*
X759093D01*
G01X755150D02*
Y240600D01*
X755610Y239980D01*
G01Y237500D02*
X754690D01*
G01X752050D02*
Y240600D01*
X752510Y239980D01*
G01Y237500D02*
X751590D01*
G01X752600Y212200D02*
Y210400D01*
G01X813942Y103151D02*
Y106251D01*
G01X812332D02*
Y103151D01*
G01Y104701D02*
X813942D01*
G01X810880Y103771D02*
X810650Y103409D01*
X810344Y103203D01*
X809999Y103151D01*
X809692Y103203D01*
X809385Y103461D01*
X809194Y103771D01*
X809155Y104081D01*
X809232Y104443D01*
X809500Y104701D01*
X809769Y104804D01*
X810114D01*
G01X809769D02*
X809539Y104959D01*
X809347Y105218D01*
X809270Y105528D01*
X809347Y105838D01*
X809539Y106096D01*
X809884Y106251D01*
X810229Y106199D01*
X810574Y105993D01*
G01X807780Y103771D02*
X807550Y103409D01*
X807244Y103203D01*
X806899Y103151D01*
X806592Y103203D01*
X806285Y103461D01*
X806094Y103771D01*
X806055Y104081D01*
X806132Y104443D01*
X806400Y104701D01*
X806669Y104804D01*
X807014D01*
G01X806669D02*
X806439Y104959D01*
X806247Y105218D01*
X806170Y105528D01*
X806247Y105838D01*
X806439Y106096D01*
X806784Y106251D01*
X807129Y106199D01*
X807474Y105993D01*
G01X813942Y328151D02*
Y331251D01*
G01X812332D02*
Y328151D01*
G01Y329701D02*
X813942D01*
G01X810880Y328771D02*
X810650Y328409D01*
X810344Y328203D01*
X809999Y328151D01*
X809692Y328203D01*
X809385Y328461D01*
X809194Y328771D01*
X809155Y329081D01*
X809232Y329443D01*
X809500Y329701D01*
X809769Y329804D01*
X810114D01*
G01X809769D02*
X809539Y329959D01*
X809347Y330218D01*
X809270Y330528D01*
X809347Y330838D01*
X809539Y331096D01*
X809884Y331251D01*
X810229Y331199D01*
X810574Y330993D01*
G01X807665Y330734D02*
X807435Y331044D01*
X807167Y331199D01*
X806860Y331251D01*
X806477Y331148D01*
X806209Y330889D01*
X806132Y330579D01*
X806170Y330269D01*
X806324Y330011D01*
X807090Y329494D01*
X807435Y329133D01*
X807665Y328616D01*
X807742Y328151D01*
X806132D01*
G01X827300Y357294D02*
X824200D01*
X824820Y357754D01*
G01X827300D02*
Y356834D01*
G01X826680Y388037D02*
X827042Y387807D01*
X827248Y387501D01*
X827300Y387156D01*
X827248Y386849D01*
X826990Y386542D01*
X826680Y386351D01*
X826370Y386312D01*
X826008Y386389D01*
X825750Y386657D01*
X825647Y386926D01*
Y387271D01*
G01Y386926D02*
X825492Y386696D01*
X825233Y386504D01*
X824923Y386427D01*
X824613Y386504D01*
X824355Y386696D01*
X824200Y387041D01*
X824252Y387386D01*
X824458Y387731D01*
G01X965669Y65689D02*
X884646D01*
Y336279D01*
X965669D01*
Y65689D01*
G01X887100Y171633D02*
X894600D01*
Y173873D01*
X894225Y174620D01*
X893350Y175180D01*
X892350Y175367D01*
X891350Y175180D01*
X890600Y174713D01*
X890225Y173873D01*
Y171633D01*
G01X887100Y179133D02*
X894600D01*
Y181467D01*
X894225Y182213D01*
X893725Y182680D01*
X892725Y182867D01*
X891725Y182680D01*
X891100Y182120D01*
X890725Y181467D01*
Y179133D01*
G01Y181467D02*
X887100Y182867D01*
G01Y190367D02*
Y186633D01*
X894600D01*
Y190367D01*
G01X890975Y188873D02*
Y186633D01*
G01X888100Y194040D02*
X887475Y194787D01*
X887100Y195627D01*
Y196373D01*
X887475Y197120D01*
X888100Y197680D01*
X888975Y197960D01*
X889850Y197773D01*
X890600Y197307D01*
X891100Y196467D01*
X891350Y195347D01*
X891850Y194693D01*
X892725Y194413D01*
X893600Y194600D01*
X894225Y195067D01*
X894600Y195720D01*
Y196373D01*
X894350Y197027D01*
X893725Y197587D01*
G01X888100Y201540D02*
X887475Y202287D01*
X887100Y203127D01*
Y203873D01*
X887475Y204620D01*
X888100Y205180D01*
X888975Y205460D01*
X889850Y205273D01*
X890600Y204807D01*
X891100Y203967D01*
X891350Y202847D01*
X891850Y202193D01*
X892725Y201913D01*
X893600Y202100D01*
X894225Y202567D01*
X894600Y203220D01*
Y203873D01*
X894350Y204527D01*
X893725Y205087D01*
G01X889600Y209787D02*
Y212213D01*
G01X887100Y216727D02*
X894600D01*
Y220273D01*
G01X890975Y218967D02*
Y216727D01*
G01X894600Y224880D02*
Y227120D01*
G01Y226000D02*
X887100D01*
G01Y224880D02*
Y227120D01*
G01X894600Y233500D02*
X887100D01*
G01X894600Y231353D02*
Y235647D01*
G01X865620Y356363D02*
X865258Y356593D01*
X865052Y356899D01*
X865000Y357244D01*
X865052Y357551D01*
X865310Y357858D01*
X865620Y358049D01*
X865930Y358088D01*
X866292Y358011D01*
X866550Y357743D01*
X866653Y357474D01*
Y357129D01*
G01Y357474D02*
X866808Y357704D01*
X867067Y357896D01*
X867377Y357973D01*
X867687Y357896D01*
X867945Y357704D01*
X868100Y357359D01*
X868048Y357014D01*
X867842Y356669D01*
G01X865000Y387106D02*
X868100D01*
X867480Y386646D01*
G01X865000D02*
Y387566D01*
G01X908300Y357294D02*
X905200D01*
X905820Y357754D01*
G01X908300D02*
Y356834D01*
G01X907680Y388037D02*
X908042Y387807D01*
X908248Y387501D01*
X908300Y387156D01*
X908248Y386849D01*
X907990Y386542D01*
X907680Y386351D01*
X907370Y386312D01*
X907008Y386389D01*
X906750Y386657D01*
X906647Y386926D01*
Y387271D01*
G01Y386926D02*
X906492Y386696D01*
X906233Y386504D01*
X905923Y386427D01*
X905613Y386504D01*
X905355Y386696D01*
X905200Y387041D01*
X905252Y387386D01*
X905458Y387731D01*
G01X932052Y103151D02*
Y106251D01*
G01X930442D02*
Y103151D01*
G01Y104701D02*
X932052D01*
G01X928990Y103771D02*
X928760Y103409D01*
X928454Y103203D01*
X928109Y103151D01*
X927802Y103203D01*
X927495Y103461D01*
X927304Y103771D01*
X927265Y104081D01*
X927342Y104443D01*
X927610Y104701D01*
X927879Y104804D01*
X928224D01*
G01X927879D02*
X927649Y104959D01*
X927457Y105218D01*
X927380Y105528D01*
X927457Y105838D01*
X927649Y106096D01*
X927994Y106251D01*
X928339Y106199D01*
X928684Y105993D01*
G01X925890Y103616D02*
X925660Y103358D01*
X925392Y103203D01*
X925047Y103151D01*
X924702Y103254D01*
X924434Y103461D01*
X924242Y103823D01*
X924204Y104236D01*
X924280Y104649D01*
X924472Y104908D01*
X924740Y105114D01*
X925009Y105166D01*
X925277Y105114D01*
X925622Y104908D01*
X925507Y106251D01*
X924472D01*
G01X932052Y328151D02*
Y331251D01*
G01X930442D02*
Y328151D01*
G01Y329701D02*
X932052D01*
G01X928990Y328771D02*
X928760Y328409D01*
X928454Y328203D01*
X928109Y328151D01*
X927802Y328203D01*
X927495Y328461D01*
X927304Y328771D01*
X927265Y329081D01*
X927342Y329443D01*
X927610Y329701D01*
X927879Y329804D01*
X928224D01*
G01X927879D02*
X927649Y329959D01*
X927457Y330218D01*
X927380Y330528D01*
X927457Y330838D01*
X927649Y331096D01*
X927994Y331251D01*
X928339Y331199D01*
X928684Y330993D01*
G01X924587Y328151D02*
Y331251D01*
X926005Y329029D01*
X924089D01*
G01X982200Y180431D02*
Y182857D01*
G01X968256Y187081D02*
X972200D01*
G01X968256Y187281D02*
X992744D01*
G01X968256Y187481D02*
X992744D01*
G01X968256Y187881D02*
X992744D01*
G01X968256Y188281D02*
X992744D01*
G01X968256Y188581D02*
X992744D01*
G01X968256Y189850D02*
Y191137D01*
G01X992744Y189324D02*
Y186700D01*
X977600D01*
G01X968256Y190237D02*
Y191437D01*
G01Y189475D02*
X992744D01*
G01X968256D02*
X992744D01*
G01X968256Y191531D02*
Y189124D01*
G01Y189514D02*
X992744D01*
G01X968256Y189475D02*
X992744D01*
G01X968256Y189081D02*
X992744D01*
G01Y189224D02*
Y226364D01*
X968256D01*
Y189324D01*
G01X984500Y210000D02*
X976500D01*
X980500Y205000D01*
X984500Y210000D01*
G01X985500Y205000D02*
X975500D01*
G01X980500D02*
Y203200D01*
G01X971300Y186700D02*
X968256D01*
Y189169D01*
G01X976800Y187081D02*
X992744D01*
G01X981100Y234173D02*
Y236413D01*
G01X982725Y235200D02*
X979475D01*
G01X968500Y229383D02*
X971600D01*
Y230303D01*
X971445Y230610D01*
X971083Y230840D01*
X970670Y230917D01*
X970257Y230840D01*
X969947Y230648D01*
X969792Y230303D01*
Y229383D01*
G01X968500Y232407D02*
X971600D01*
Y233173D01*
X971445Y233480D01*
X971238Y233710D01*
X970928Y233902D01*
X970567Y234055D01*
X970050Y234093D01*
X969533Y234055D01*
X969172Y233902D01*
X968862Y233710D01*
X968655Y233480D01*
X968500Y233173D01*
Y232407D01*
G01X968862Y235698D02*
X968603Y235967D01*
X968500Y236273D01*
X968603Y236580D01*
X968913Y236848D01*
X969378Y237040D01*
X969843Y237117D01*
X970412D01*
X970877Y237040D01*
X971290Y236848D01*
X971497Y236618D01*
X971600Y236350D01*
X971497Y236043D01*
X971290Y235813D01*
X970980Y235660D01*
X970567Y235583D01*
X970205Y235660D01*
X969843Y235852D01*
X969637Y236082D01*
X969585Y236350D01*
X969688Y236657D01*
X969947Y236887D01*
X970412Y237117D01*
G01X980500Y212200D02*
Y210400D01*
G01X986750Y183806D02*
X1001250D01*
Y133194D01*
X986750D01*
Y183806D01*
G01X1003000Y174422D02*
X1006100D01*
Y175878D01*
G01X1004602Y175342D02*
Y174422D01*
G01X1003413Y177445D02*
X1003155Y177752D01*
X1003000Y178097D01*
Y178403D01*
X1003155Y178710D01*
X1003413Y178940D01*
X1003775Y179055D01*
X1004137Y178978D01*
X1004447Y178787D01*
X1004653Y178442D01*
X1004757Y177982D01*
X1004963Y177713D01*
X1005325Y177598D01*
X1005687Y177675D01*
X1005945Y177867D01*
X1006100Y178135D01*
Y178403D01*
X1005997Y178672D01*
X1005738Y178902D01*
G01X1003465Y180507D02*
X1003207Y180737D01*
X1003052Y181005D01*
X1003000Y181350D01*
X1003103Y181695D01*
X1003310Y181963D01*
X1003672Y182155D01*
X1004085Y182193D01*
X1004498Y182117D01*
X1004757Y181925D01*
X1004963Y181657D01*
X1005015Y181388D01*
X1004963Y181120D01*
X1004757Y180775D01*
X1006100Y180890D01*
Y181925D01*
G01X1008700Y180431D02*
Y182857D01*
G01X994756Y187081D02*
X1011100D01*
G01X994756Y187281D02*
X1019244D01*
G01X994756Y187481D02*
X1019244D01*
G01X994756Y187881D02*
X1019244D01*
G01X994756Y188281D02*
X1019244D01*
G01X994756Y188581D02*
X1019244D01*
G01X994756Y189850D02*
Y191137D01*
G01Y190237D02*
Y191437D01*
G01Y189475D02*
X1019244D01*
G01X994756D02*
X1019244D01*
G01X994756Y191531D02*
Y189124D01*
G01Y189514D02*
X1019244D01*
G01X994756Y189475D02*
X1019244D01*
G01X994756Y189081D02*
X1019244D01*
G01Y189224D02*
Y226364D01*
X994756D01*
Y189324D01*
G01X1011000Y210000D02*
X1003000D01*
X1007000Y205000D01*
X1011000Y210000D01*
G01X1012000Y205000D02*
X1002000D01*
G01X1007000D02*
Y203200D01*
G01X1011200Y186700D02*
X994756D01*
Y189169D01*
G01X992744Y189124D02*
Y194004D01*
G01Y189324D02*
Y189850D01*
G01Y191637D02*
Y191531D01*
G01X992451Y189437D02*
X992251Y189450D01*
G01X1007600Y234173D02*
Y236413D01*
G01X1009225Y235200D02*
X1005975D01*
G01X1007000Y212200D02*
Y210400D01*
G01X992233Y583155D02*
Y556929D01*
X1026809Y570042D01*
X992233Y583155D01*
G01X987620Y575383D02*
X987310Y575575D01*
X987103Y575805D01*
X987000Y576073D01*
X987103Y576380D01*
X987310Y576610D01*
X987620Y576840D01*
X988033Y576917D01*
X990100D01*
G01X987000Y579250D02*
X990100D01*
X989480Y578790D01*
G01X987000D02*
Y579710D01*
G01Y582810D02*
X990100D01*
X987878Y581392D01*
Y583308D01*
G01X1021000Y201200D02*
X1031200D01*
Y205800D01*
X1021000D01*
Y201200D01*
G01X1021300Y187000D02*
X1027900D01*
Y200000D01*
X1021300D01*
Y187000D01*
G01X1023000Y206900D02*
X1029200D01*
Y210100D01*
X1023000D01*
Y206900D01*
G01X1019244Y189324D02*
Y186700D01*
X1014700D01*
G01X1019244Y189124D02*
Y194004D01*
G01Y189324D02*
Y189850D01*
G01Y191637D02*
Y191531D01*
G01X1018951Y189437D02*
X1018751Y189450D01*
G01X1015000Y187081D02*
X1019244D01*
G01X1029200Y214100D02*
X1023000D01*
Y210900D01*
X1029200D01*
Y214100D01*
G01X1016000Y228383D02*
X1019100D01*
Y229303D01*
X1018945Y229610D01*
X1018583Y229840D01*
X1018170Y229917D01*
X1017757Y229840D01*
X1017447Y229648D01*
X1017292Y229303D01*
Y228383D01*
G01X1016000Y231407D02*
X1019100D01*
Y232173D01*
X1018945Y232480D01*
X1018738Y232710D01*
X1018428Y232902D01*
X1018067Y233055D01*
X1017550Y233093D01*
X1017033Y233055D01*
X1016672Y232902D01*
X1016362Y232710D01*
X1016155Y232480D01*
X1016000Y232173D01*
Y231407D01*
G01Y235273D02*
X1016672Y235350D01*
X1017240Y235465D01*
X1017757Y235618D01*
X1018325Y235810D01*
X1019100Y236117D01*
Y234583D01*
G01X1029400Y263300D02*
X1036800D01*
Y280700D01*
X1029400D01*
Y263300D01*
G01X1031600Y250300D02*
Y243700D01*
X1044600D01*
Y250300D01*
X1031600D01*
G01X1032950Y315799D02*
Y298201D01*
X1040250D01*
Y315799D01*
X1032950D01*
G01X1059800Y229000D02*
X1066400D01*
Y242000D01*
X1059800D01*
Y229000D01*
G01X1068800D02*
X1075400D01*
Y242000D01*
X1068800D01*
Y229000D01*
G01X1058600Y244000D02*
Y250000D01*
X1046600D01*
Y244000D01*
X1058600D01*
G01X1066200Y247100D02*
X1060000D01*
Y243900D01*
X1066200D01*
Y247100D01*
G01X1069000Y243900D02*
X1075200D01*
Y247100D01*
X1069000D01*
Y243900D01*
G01X1070700Y251600D02*
X1064500D01*
Y248400D01*
X1070700D01*
Y251600D01*
G01X1056117Y253500D02*
Y256600D01*
X1055197D01*
X1054890Y256445D01*
X1054660Y256083D01*
X1054583Y255670D01*
X1054660Y255257D01*
X1054852Y254947D01*
X1055197Y254792D01*
X1056117D01*
G01X1053093Y256600D02*
Y254378D01*
X1052940Y253913D01*
X1052633Y253603D01*
X1052250Y253500D01*
X1051867Y253603D01*
X1051560Y253913D01*
X1051407Y254378D01*
Y256600D01*
G01X1049227Y253500D02*
X1049150Y254172D01*
X1049035Y254740D01*
X1048882Y255257D01*
X1048690Y255825D01*
X1048383Y256600D01*
X1049917D01*
G01X1049800Y260024D02*
X1047655D01*
Y262100D01*
G01X1063500Y260024D02*
X1059700D01*
G01X1075700Y297900D02*
Y304100D01*
X1072500D01*
Y297900D01*
X1075700D01*
G01X1064200D02*
Y304100D01*
X1061000D01*
Y297900D01*
X1064200D01*
G01X1059700Y287976D02*
X1063500D01*
G01X1047655Y285900D02*
Y287976D01*
X1049800D01*
G01X1051400Y298300D02*
X1058800D01*
Y315700D01*
X1051400D01*
Y298300D01*
G01X1075900Y338000D02*
X1069300D01*
Y325000D01*
X1075900D01*
Y338000D01*
G01X1067900D02*
X1061300D01*
Y325000D01*
X1067900D01*
Y338000D01*
G01X1071700Y302600D02*
X1065500D01*
Y299400D01*
X1071700D01*
Y302600D01*
G01X1071500Y363800D02*
Y357200D01*
X1084500D01*
Y363800D01*
X1071500D01*
G01X1099200Y261100D02*
X1093000D01*
Y257900D01*
X1099200D01*
Y261100D01*
G01Y257100D02*
X1093000D01*
Y253900D01*
X1099200D01*
Y257100D01*
G01X1093000Y245900D02*
X1099200D01*
Y249100D01*
X1093000D01*
Y245900D01*
G01Y249900D02*
X1099200D01*
Y253100D01*
X1093000D01*
Y249900D01*
G01X1099200Y269100D02*
X1093000D01*
Y265900D01*
X1099200D01*
Y269100D01*
G01Y265100D02*
X1093000D01*
Y261900D01*
X1099200D01*
Y265100D01*
G01Y245100D02*
X1093000D01*
Y241900D01*
X1099200D01*
Y245100D01*
G01X1079545Y262100D02*
Y260024D01*
G01D02*
X1077400D01*
G01X1089000Y275700D02*
X1099200D01*
Y280300D01*
X1089000D01*
Y275700D01*
G01X1094500Y295900D02*
X1100700D01*
Y299100D01*
X1094500D01*
Y295900D01*
G01X1083700Y297900D02*
Y304100D01*
X1080500D01*
Y297900D01*
X1083700D01*
G01X1094500Y287900D02*
X1100700D01*
Y291100D01*
X1094500D01*
Y287900D01*
G01X1099200Y273100D02*
X1093000D01*
Y269900D01*
X1099200D01*
Y273100D01*
G01X1095200Y284600D02*
X1089000D01*
Y281400D01*
X1095200D01*
Y284600D01*
G01X1096500Y283400D02*
X1102700D01*
Y286600D01*
X1096500D01*
Y283400D01*
G01X1087700Y297900D02*
Y304100D01*
X1084500D01*
Y297900D01*
X1087700D01*
G01X1079700D02*
Y304100D01*
X1076500D01*
Y297900D01*
X1079700D01*
G01X1091700D02*
Y304100D01*
X1088500D01*
Y297900D01*
X1091700D01*
G01X1094500Y291900D02*
X1100700D01*
Y295100D01*
X1094500D01*
Y291900D01*
G01X1077400Y287976D02*
X1079545D01*
Y285900D01*
G01X1107100Y308700D02*
Y315300D01*
X1094100D01*
Y308700D01*
X1107100D01*
G01X1091400Y338000D02*
X1084800D01*
Y325000D01*
X1091400D01*
Y338000D01*
G01X1083900D02*
X1077300D01*
Y325000D01*
X1083900D01*
Y338000D01*
G01X1124200Y250800D02*
X1114000D01*
Y246200D01*
X1124200D01*
Y250800D01*
G01X1122500Y261900D02*
X1128700D01*
Y265100D01*
X1122500D01*
Y261900D01*
G01X1125500Y260100D02*
Y253900D01*
X1128700D01*
Y260100D01*
X1125500D01*
G01X1122200Y245100D02*
X1116000D01*
Y241900D01*
X1122200D01*
Y245100D01*
G01X1125500Y252100D02*
Y245900D01*
X1128700D01*
Y252100D01*
X1125500D01*
G01X1135700Y271600D02*
X1129500D01*
Y268400D01*
X1135700D01*
Y271600D01*
G01X1128700Y269100D02*
X1122500D01*
Y265900D01*
X1128700D01*
Y269100D01*
G01X1124200Y260100D02*
X1118000D01*
Y256900D01*
X1124200D01*
Y260100D01*
G01Y255600D02*
X1118000D01*
Y252400D01*
X1124200D01*
Y255600D01*
G01X1128700Y269900D02*
Y276100D01*
X1125500D01*
Y269900D01*
X1128700D01*
G01X1124700Y276100D02*
X1118500D01*
Y272900D01*
X1124700D01*
Y276100D01*
G01X1122500Y276900D02*
X1128700D01*
Y280100D01*
X1122500D01*
Y276900D01*
G01Y281400D02*
X1128700D01*
Y284600D01*
X1122500D01*
Y281400D01*
G01Y285900D02*
X1128700D01*
Y289100D01*
X1122500D01*
Y285900D01*
G01Y290400D02*
X1128700D01*
Y293600D01*
X1122500D01*
Y290400D01*
G01X1133600Y312200D02*
X1136502Y315102D01*
X1142458D01*
Y302898D01*
X1124742D01*
Y315102D01*
X1130698D01*
X1133600Y312200D01*
G01X1141800Y317300D02*
Y324700D01*
X1124400D01*
Y317300D01*
X1141800D01*
G01X1109300Y353400D02*
Y363600D01*
X1104700D01*
Y353400D01*
X1109300D01*
G01X1109700Y343000D02*
X1116300D01*
Y356000D01*
X1109700D01*
Y343000D01*
G01X1114100Y357400D02*
Y363600D01*
X1110900D01*
Y357400D01*
X1114100D01*
G01X1136600Y359400D02*
Y365600D01*
X1133400D01*
Y359400D01*
X1136600D01*
G01X1123500Y359000D02*
X1120898Y356398D01*
X1116676D01*
Y368602D01*
X1130324D01*
Y356398D01*
X1126102D01*
X1123500Y359000D01*
G01X1152900Y243200D02*
Y235800D01*
X1170300D01*
Y243200D01*
X1152900D01*
G01X1148000Y242600D02*
Y236400D01*
X1151200D01*
Y242600D01*
X1148000D01*
G01X1144000D02*
Y236400D01*
X1147200D01*
Y242600D01*
X1144000D01*
G01X1151200Y244900D02*
Y251100D01*
X1148000D01*
Y244900D01*
X1151200D01*
G01X1147200D02*
Y251100D01*
X1144000D01*
Y244900D01*
X1147200D01*
G01X1138500Y251100D02*
Y244900D01*
X1141700D01*
Y251100D01*
X1138500D01*
G01X1158700D02*
X1152500D01*
Y247900D01*
X1158700D01*
Y251100D01*
G01X1141624Y264100D02*
Y262024D01*
X1143700D01*
G01X1159660D02*
X1165300D01*
G01X1156200Y297900D02*
Y304100D01*
X1153000D01*
Y297900D01*
X1156200D01*
G01X1143700Y289976D02*
X1141624D01*
G01X1165300D02*
X1159660D01*
G01X1141624D02*
Y287900D01*
G01X1158500Y316383D02*
X1161600D01*
Y317303D01*
X1161445Y317610D01*
X1161083Y317840D01*
X1160670Y317917D01*
X1160257Y317840D01*
X1159947Y317648D01*
X1159792Y317303D01*
Y316383D01*
G01X1159120Y319483D02*
X1158810Y319675D01*
X1158603Y319905D01*
X1158500Y320173D01*
X1158603Y320480D01*
X1158810Y320710D01*
X1159120Y320940D01*
X1159533Y321017D01*
X1161600D01*
G01X1158500Y323350D02*
X1161600D01*
X1160980Y322890D01*
G01X1158500D02*
Y323810D01*
G01X1159200Y308100D02*
X1153000D01*
Y304900D01*
X1159200D01*
Y308100D01*
G01X1149100Y316807D02*
X1146878D01*
X1146413Y316960D01*
X1146103Y317267D01*
X1146000Y317650D01*
X1146103Y318033D01*
X1146413Y318340D01*
X1146878Y318493D01*
X1149100D01*
G01X1146620Y319907D02*
X1146258Y320137D01*
X1146052Y320443D01*
X1146000Y320788D01*
X1146052Y321095D01*
X1146310Y321402D01*
X1146620Y321593D01*
X1146930Y321632D01*
X1147292Y321555D01*
X1147550Y321287D01*
X1147653Y321018D01*
Y320673D01*
G01Y321018D02*
X1147808Y321248D01*
X1148067Y321440D01*
X1148377Y321517D01*
X1148687Y321440D01*
X1148945Y321248D01*
X1149100Y320903D01*
X1149048Y320558D01*
X1148842Y320213D01*
G01X1146000Y323850D02*
X1149100D01*
X1148480Y323390D01*
G01X1146000D02*
Y324310D01*
G01X1161400Y349100D02*
Y342900D01*
X1164600D01*
Y349100D01*
X1161400D01*
G01X1140600Y359400D02*
Y365600D01*
X1137400D01*
Y359400D01*
X1140600D01*
G01X1167100Y339600D02*
X1160900D01*
Y336400D01*
X1167100D01*
Y339600D01*
G01X1143443Y358050D02*
Y355828D01*
X1143290Y355363D01*
X1142983Y355053D01*
X1142600Y354950D01*
X1142217Y355053D01*
X1141910Y355363D01*
X1141757Y355828D01*
Y358050D01*
G01X1140343Y355570D02*
X1140113Y355208D01*
X1139807Y355002D01*
X1139462Y354950D01*
X1139155Y355002D01*
X1138848Y355260D01*
X1138657Y355570D01*
X1138618Y355880D01*
X1138695Y356242D01*
X1138963Y356500D01*
X1139232Y356603D01*
X1139577D01*
G01X1139232D02*
X1139002Y356758D01*
X1138810Y357017D01*
X1138733Y357327D01*
X1138810Y357637D01*
X1139002Y357895D01*
X1139347Y358050D01*
X1139692Y357998D01*
X1140037Y357792D01*
G01X1135940Y354950D02*
Y358050D01*
X1137358Y355828D01*
X1135442D01*
G01X1152443Y334050D02*
Y331828D01*
X1152290Y331363D01*
X1151983Y331053D01*
X1151600Y330950D01*
X1151217Y331053D01*
X1150910Y331363D01*
X1150757Y331828D01*
Y334050D01*
G01X1148040Y330950D02*
Y334050D01*
X1149458Y331828D01*
X1147542D01*
G01X1146128Y333533D02*
X1145898Y333843D01*
X1145630Y333998D01*
X1145323Y334050D01*
X1144940Y333947D01*
X1144672Y333688D01*
X1144595Y333378D01*
X1144633Y333068D01*
X1144787Y332810D01*
X1145553Y332293D01*
X1145898Y331932D01*
X1146128Y331415D01*
X1146205Y330950D01*
X1144595D01*
G01X1159512Y336169D02*
X1148488D01*
G01X1159512D02*
Y344831D01*
X1148488D01*
Y336169D01*
G01X1167500Y262024D02*
X1169576D01*
Y264100D01*
G01X1238428Y300181D02*
G03I-25950J0D01*
G01X1179617Y294500D02*
Y297600D01*
X1178697D01*
X1178390Y297445D01*
X1178160Y297083D01*
X1178083Y296670D01*
X1178160Y296257D01*
X1178352Y295947D01*
X1178697Y295792D01*
X1179617D01*
G01X1176593Y297600D02*
Y295378D01*
X1176440Y294913D01*
X1176133Y294603D01*
X1175750Y294500D01*
X1175367Y294603D01*
X1175060Y294913D01*
X1174907Y295378D01*
Y297600D01*
G01X1172650Y294500D02*
Y297600D01*
X1173110Y296980D01*
G01Y294500D02*
X1172190D01*
G01X1169576Y276100D02*
Y281800D01*
G01Y287900D02*
Y289976D01*
X1167500D01*
G01X1177100Y308700D02*
Y315300D01*
X1164100D01*
Y308700D01*
X1177100D01*
G01Y299700D02*
Y306300D01*
X1164100D01*
Y299700D01*
X1177100D01*
G01X1177600Y351900D02*
Y358100D01*
X1174400D01*
Y351900D01*
X1177600D01*
G01X1172100D02*
Y358100D01*
X1168900D01*
Y351900D01*
X1172100D01*
G01X1169169Y359488D02*
Y370512D01*
G01Y359488D02*
X1177831D01*
Y370512D01*
X1169169D01*
G01X1182943Y375050D02*
Y372828D01*
X1182790Y372363D01*
X1182483Y372053D01*
X1182100Y371950D01*
X1181717Y372053D01*
X1181410Y372363D01*
X1181257Y372828D01*
Y375050D01*
G01X1178540Y371950D02*
Y375050D01*
X1179958Y372828D01*
X1178042D01*
G01X1176743Y372570D02*
X1176513Y372208D01*
X1176207Y372002D01*
X1175862Y371950D01*
X1175555Y372002D01*
X1175248Y372260D01*
X1175057Y372570D01*
X1175018Y372880D01*
X1175095Y373242D01*
X1175363Y373500D01*
X1175632Y373603D01*
X1175977D01*
G01X1175632D02*
X1175402Y373758D01*
X1175210Y374017D01*
X1175133Y374327D01*
X1175210Y374637D01*
X1175402Y374895D01*
X1175747Y375050D01*
X1176092Y374998D01*
X1176437Y374792D01*
G01X1342700Y147100D02*
Y136900D01*
X1347300D01*
Y147100D01*
X1342700D01*
G01X1347100Y147600D02*
Y157800D01*
X1342500D01*
Y147600D01*
X1347100D01*
G01X1334000Y142273D02*
Y144513D01*
G01X1335625Y143300D02*
X1332375D01*
G01X1327000Y139383D02*
X1330100D01*
Y140303D01*
X1329945Y140610D01*
X1329583Y140840D01*
X1329170Y140917D01*
X1328757Y140840D01*
X1328447Y140648D01*
X1328292Y140303D01*
Y139383D01*
G01X1327000Y142407D02*
X1330100D01*
Y143173D01*
X1329945Y143480D01*
X1329738Y143710D01*
X1329428Y143902D01*
X1329067Y144055D01*
X1328550Y144093D01*
X1328033Y144055D01*
X1327672Y143902D01*
X1327362Y143710D01*
X1327155Y143480D01*
X1327000Y143173D01*
Y142407D01*
G01Y146350D02*
X1330100D01*
X1329480Y145890D01*
G01X1327000D02*
Y146810D01*
G01X1328292Y148722D02*
X1328653Y148990D01*
X1328860Y149220D01*
X1328963Y149527D01*
X1328860Y149795D01*
X1328653Y149987D01*
X1328343Y150140D01*
X1327982Y150178D01*
X1327672Y150140D01*
X1327362Y149987D01*
X1327103Y149757D01*
X1327000Y149488D01*
X1327103Y149182D01*
X1327413Y148913D01*
X1327878Y148760D01*
X1328395Y148722D01*
X1329067Y148798D01*
X1329428Y148913D01*
X1329790Y149105D01*
X1330048Y149373D01*
X1330100Y149642D01*
X1329997Y149910D01*
X1329738Y150102D01*
G01X1349200Y162600D02*
X1339000D01*
Y158000D01*
X1349200D01*
Y162600D01*
G01X1325700Y151900D02*
Y158100D01*
X1322500D01*
Y151900D01*
X1325700D01*
G01X1326500Y158100D02*
Y151900D01*
X1329700D01*
Y158100D01*
X1326500D01*
G01X1334200Y163287D02*
Y165713D01*
G01X1336800Y162000D02*
X1331400D01*
G01Y161500D02*
X1336800D01*
G01Y161000D02*
X1331400D01*
G01X1336900Y148000D02*
Y162500D01*
X1331300D01*
Y148000D01*
X1336900D01*
G01X1336069Y153319D02*
X1332131D01*
X1334100Y155287D01*
X1336069Y153319D01*
G01Y155681D02*
X1332131D01*
G01X1338500Y154800D02*
Y148600D01*
X1341700D01*
Y154800D01*
X1338500D01*
G01X1349200Y206700D02*
X1339000D01*
Y202100D01*
X1349200D01*
Y206700D01*
G01X1342200Y191100D02*
Y180900D01*
X1346800D01*
Y191100D01*
X1342200D01*
G01X1322500Y202500D02*
Y196300D01*
X1325700D01*
Y202500D01*
X1322500D01*
G01X1326500D02*
Y196300D01*
X1329700D01*
Y202500D01*
X1326500D01*
G01X1347100Y191500D02*
Y201700D01*
X1342500D01*
Y191500D01*
X1347100D01*
G01X1336000Y189273D02*
Y191513D01*
G01X1337625Y190300D02*
X1334375D01*
G01X1334200Y207687D02*
Y210113D01*
G01X1326500Y183383D02*
X1329600D01*
Y184303D01*
X1329445Y184610D01*
X1329083Y184840D01*
X1328670Y184917D01*
X1328257Y184840D01*
X1327947Y184648D01*
X1327792Y184303D01*
Y183383D01*
G01X1326500Y186407D02*
X1329600D01*
Y187173D01*
X1329445Y187480D01*
X1329238Y187710D01*
X1328928Y187902D01*
X1328567Y188055D01*
X1328050Y188093D01*
X1327533Y188055D01*
X1327172Y187902D01*
X1326862Y187710D01*
X1326655Y187480D01*
X1326500Y187173D01*
Y186407D01*
G01Y190350D02*
X1329600D01*
X1328980Y189890D01*
G01X1326500D02*
Y190810D01*
G01X1326965Y192607D02*
X1326707Y192837D01*
X1326552Y193105D01*
X1326500Y193450D01*
X1326603Y193795D01*
X1326810Y194063D01*
X1327172Y194255D01*
X1327585Y194293D01*
X1327998Y194217D01*
X1328257Y194025D01*
X1328463Y193757D01*
X1328515Y193488D01*
X1328463Y193220D01*
X1328257Y192875D01*
X1329600Y192990D01*
Y194025D01*
G01X1336800Y206400D02*
X1331400D01*
G01Y205900D02*
X1336800D01*
G01Y205400D02*
X1331400D01*
G01X1336900Y192400D02*
Y206900D01*
X1331300D01*
Y192400D01*
X1336900D01*
G01X1336069Y197719D02*
X1332131D01*
X1334100Y199687D01*
X1336069Y197719D01*
G01Y200081D02*
X1332131D01*
G01X1339000Y199000D02*
Y192800D01*
X1342200D01*
Y199000D01*
X1339000D01*
G01X1347400Y147200D02*
X1357600D01*
Y151800D01*
X1347400D01*
Y147200D01*
G01Y191700D02*
X1357600D01*
Y196300D01*
X1347400D01*
Y191700D01*
G01X1511673Y41595D02*
Y-10571D01*
X1411162D01*
Y41595D01*
X1511673D01*
G01X1491667Y27000D02*
Y34500D01*
X1489427D01*
X1488680Y34125D01*
X1488120Y33250D01*
X1487933Y32250D01*
X1488120Y31250D01*
X1488587Y30500D01*
X1489427Y30125D01*
X1491667D01*
G01X1484167Y27000D02*
Y34500D01*
X1481833D01*
X1481087Y34125D01*
X1480620Y33625D01*
X1480433Y32625D01*
X1480620Y31625D01*
X1481180Y31000D01*
X1481833Y30625D01*
X1484167D01*
G01X1481833D02*
X1480433Y27000D01*
G01X1472933D02*
X1476667D01*
Y34500D01*
X1472933D01*
G01X1474427Y30875D02*
X1476667D01*
G01X1469260Y28000D02*
X1468513Y27375D01*
X1467673Y27000D01*
X1466927D01*
X1466180Y27375D01*
X1465620Y28000D01*
X1465340Y28875D01*
X1465527Y29750D01*
X1465993Y30500D01*
X1466833Y31000D01*
X1467953Y31250D01*
X1468607Y31750D01*
X1468887Y32625D01*
X1468700Y33500D01*
X1468233Y34125D01*
X1467580Y34500D01*
X1466927D01*
X1466273Y34250D01*
X1465713Y33625D01*
G01X1461760Y28000D02*
X1461013Y27375D01*
X1460173Y27000D01*
X1459427D01*
X1458680Y27375D01*
X1458120Y28000D01*
X1457840Y28875D01*
X1458027Y29750D01*
X1458493Y30500D01*
X1459333Y31000D01*
X1460453Y31250D01*
X1461107Y31750D01*
X1461387Y32625D01*
X1461200Y33500D01*
X1460733Y34125D01*
X1460080Y34500D01*
X1459427D01*
X1458773Y34250D01*
X1458213Y33625D01*
G01X1453513Y29500D02*
X1451087D01*
G01X1446573Y27000D02*
Y34500D01*
X1443027D01*
G01X1444333Y30875D02*
X1446573D01*
G01X1438420Y34500D02*
X1436180D01*
G01X1437300D02*
Y27000D01*
G01X1438420D02*
X1436180D01*
G01X1429800Y34500D02*
Y27000D01*
G01X1431947Y34500D02*
X1427653D01*
G01X1476667Y601000D02*
Y608500D01*
X1474427D01*
X1473680Y608125D01*
X1473120Y607250D01*
X1472933Y606250D01*
X1473120Y605250D01*
X1473587Y604500D01*
X1474427Y604125D01*
X1476667D01*
G01X1469167Y601000D02*
Y608500D01*
X1466833D01*
X1466087Y608125D01*
X1465620Y607625D01*
X1465433Y606625D01*
X1465620Y605625D01*
X1466180Y605000D01*
X1466833Y604625D01*
X1469167D01*
G01X1466833D02*
X1465433Y601000D01*
G01X1457933D02*
X1461667D01*
Y608500D01*
X1457933D01*
G01X1459427Y604875D02*
X1461667D01*
G01X1454260Y602000D02*
X1453513Y601375D01*
X1452673Y601000D01*
X1451927D01*
X1451180Y601375D01*
X1450620Y602000D01*
X1450340Y602875D01*
X1450527Y603750D01*
X1450993Y604500D01*
X1451833Y605000D01*
X1452953Y605250D01*
X1453607Y605750D01*
X1453887Y606625D01*
X1453700Y607500D01*
X1453233Y608125D01*
X1452580Y608500D01*
X1451927D01*
X1451273Y608250D01*
X1450713Y607625D01*
G01X1446760Y602000D02*
X1446013Y601375D01*
X1445173Y601000D01*
X1444427D01*
X1443680Y601375D01*
X1443120Y602000D01*
X1442840Y602875D01*
X1443027Y603750D01*
X1443493Y604500D01*
X1444333Y605000D01*
X1445453Y605250D01*
X1446107Y605750D01*
X1446387Y606625D01*
X1446200Y607500D01*
X1445733Y608125D01*
X1445080Y608500D01*
X1444427D01*
X1443773Y608250D01*
X1443213Y607625D01*
G01X1438513Y603500D02*
X1436087D01*
G01X1431573Y601000D02*
Y608500D01*
X1428027D01*
G01X1429333Y604875D02*
X1431573D01*
G01X1423420Y608500D02*
X1421180D01*
G01X1422300D02*
Y601000D01*
G01X1423420D02*
X1421180D01*
G01X1414800Y608500D02*
Y601000D01*
G01X1416947Y608500D02*
X1412653D01*
G01X1503642Y590473D02*
X1409744D01*
G01D02*
Y729449D01*
G01X1423585Y626557D02*
X1423815Y626712D01*
X1424083Y626815D01*
X1424390D01*
X1424735Y626660D01*
X1425003Y626402D01*
X1425195Y626092D01*
X1425348Y625575D01*
X1425386Y625110D01*
X1425310Y624645D01*
X1425195Y624335D01*
X1424965Y624025D01*
X1424696Y623818D01*
X1424428Y623715D01*
X1424160D01*
X1423891Y623818D01*
X1423661Y623973D01*
X1423470Y624180D01*
G01X1422171D02*
X1421941Y623922D01*
X1421673Y623767D01*
X1421328Y623715D01*
X1420983Y623818D01*
X1420715Y624025D01*
X1420523Y624387D01*
X1420485Y624800D01*
X1420561Y625213D01*
X1420753Y625472D01*
X1421021Y625678D01*
X1421290Y625730D01*
X1421558Y625678D01*
X1421903Y625472D01*
X1421788Y626815D01*
X1420753D01*
G01X1423585Y634431D02*
X1423815Y634586D01*
X1424083Y634689D01*
X1424390D01*
X1424735Y634534D01*
X1425003Y634276D01*
X1425195Y633966D01*
X1425348Y633449D01*
X1425386Y632984D01*
X1425310Y632519D01*
X1425195Y632209D01*
X1424965Y631899D01*
X1424696Y631692D01*
X1424428Y631589D01*
X1424160D01*
X1423891Y631692D01*
X1423661Y631847D01*
X1423470Y632054D01*
G01X1420868Y631589D02*
Y634689D01*
X1422286Y632467D01*
X1420370D01*
G01X1423585Y618683D02*
X1423815Y618838D01*
X1424083Y618941D01*
X1424390D01*
X1424735Y618786D01*
X1425003Y618528D01*
X1425195Y618218D01*
X1425348Y617701D01*
X1425386Y617236D01*
X1425310Y616771D01*
X1425195Y616461D01*
X1424965Y616151D01*
X1424696Y615944D01*
X1424428Y615841D01*
X1424160D01*
X1423891Y615944D01*
X1423661Y616099D01*
X1423470Y616306D01*
G01X1422056Y617133D02*
X1421788Y617494D01*
X1421558Y617701D01*
X1421251Y617804D01*
X1420983Y617701D01*
X1420791Y617494D01*
X1420638Y617184D01*
X1420600Y616823D01*
X1420638Y616513D01*
X1420791Y616203D01*
X1421021Y615944D01*
X1421290Y615841D01*
X1421596Y615944D01*
X1421865Y616254D01*
X1422018Y616719D01*
X1422056Y617236D01*
X1421980Y617908D01*
X1421865Y618269D01*
X1421673Y618631D01*
X1421405Y618889D01*
X1421136Y618941D01*
X1420868Y618838D01*
X1420676Y618579D01*
G01X1425271Y655211D02*
Y658311D01*
X1424505D01*
X1424198Y658156D01*
X1423968Y657949D01*
X1423776Y657639D01*
X1423623Y657278D01*
X1423585Y656761D01*
X1423623Y656244D01*
X1423776Y655883D01*
X1423968Y655573D01*
X1424198Y655366D01*
X1424505Y655211D01*
X1425271D01*
G01X1422171Y655676D02*
X1421941Y655418D01*
X1421673Y655263D01*
X1421328Y655211D01*
X1420983Y655314D01*
X1420715Y655521D01*
X1420523Y655883D01*
X1420485Y656296D01*
X1420561Y656709D01*
X1420753Y656968D01*
X1421021Y657174D01*
X1421290Y657226D01*
X1421558Y657174D01*
X1421903Y656968D01*
X1421788Y658311D01*
X1420753D01*
G01X1425271Y647337D02*
Y650437D01*
X1424505D01*
X1424198Y650282D01*
X1423968Y650075D01*
X1423776Y649765D01*
X1423623Y649404D01*
X1423585Y648887D01*
X1423623Y648370D01*
X1423776Y648009D01*
X1423968Y647699D01*
X1424198Y647492D01*
X1424505Y647337D01*
X1425271D01*
G01X1422056Y648629D02*
X1421788Y648990D01*
X1421558Y649197D01*
X1421251Y649300D01*
X1420983Y649197D01*
X1420791Y648990D01*
X1420638Y648680D01*
X1420600Y648319D01*
X1420638Y648009D01*
X1420791Y647699D01*
X1421021Y647440D01*
X1421290Y647337D01*
X1421596Y647440D01*
X1421865Y647750D01*
X1422018Y648215D01*
X1422056Y648732D01*
X1421980Y649404D01*
X1421865Y649765D01*
X1421673Y650127D01*
X1421405Y650385D01*
X1421136Y650437D01*
X1420868Y650334D01*
X1420676Y650075D01*
G01X1425271Y663085D02*
Y666185D01*
X1424505D01*
X1424198Y666030D01*
X1423968Y665823D01*
X1423776Y665513D01*
X1423623Y665152D01*
X1423585Y664635D01*
X1423623Y664118D01*
X1423776Y663757D01*
X1423968Y663447D01*
X1424198Y663240D01*
X1424505Y663085D01*
X1425271D01*
G01X1420868D02*
Y666185D01*
X1422286Y663963D01*
X1420370D01*
G01X1409744Y729449D02*
X1503642D01*
G01X1489271Y590473D02*
Y729449D01*
G01X1559547Y590473D02*
X1489271D01*
G01X1495598Y616015D02*
X1494640Y619115D01*
X1493682Y616015D01*
G01X1494027Y617100D02*
X1495253D01*
G01X1491540Y616015D02*
Y619115D01*
X1492000Y618495D01*
G01Y616015D02*
X1491080D01*
G01X1495498Y623815D02*
X1494540Y626915D01*
X1493582Y623815D01*
G01X1493927Y624900D02*
X1495153D01*
G01X1492168Y626398D02*
X1491938Y626708D01*
X1491670Y626863D01*
X1491363Y626915D01*
X1490980Y626812D01*
X1490712Y626553D01*
X1490635Y626243D01*
X1490673Y625933D01*
X1490827Y625675D01*
X1491593Y625158D01*
X1491938Y624797D01*
X1492168Y624280D01*
X1492245Y623815D01*
X1490635D01*
G01X1495498Y631689D02*
X1494540Y634789D01*
X1493582Y631689D01*
G01X1493927Y632774D02*
X1495153D01*
G01X1492283Y632309D02*
X1492053Y631947D01*
X1491747Y631741D01*
X1491402Y631689D01*
X1491095Y631741D01*
X1490788Y631999D01*
X1490597Y632309D01*
X1490558Y632619D01*
X1490635Y632981D01*
X1490903Y633239D01*
X1491172Y633342D01*
X1491517D01*
G01X1491172D02*
X1490942Y633497D01*
X1490750Y633756D01*
X1490673Y634066D01*
X1490750Y634376D01*
X1490942Y634634D01*
X1491287Y634789D01*
X1491632Y634737D01*
X1491977Y634531D01*
G01X1495268Y655311D02*
Y658411D01*
X1493812D01*
G01X1494348Y656913D02*
X1495268D01*
G01X1492168Y657894D02*
X1491938Y658204D01*
X1491670Y658359D01*
X1491363Y658411D01*
X1490980Y658308D01*
X1490712Y658049D01*
X1490635Y657739D01*
X1490673Y657429D01*
X1490827Y657171D01*
X1491593Y656654D01*
X1491938Y656293D01*
X1492168Y655776D01*
X1492245Y655311D01*
X1490635D01*
G01X1495268Y647437D02*
Y650537D01*
X1493812D01*
G01X1494348Y649039D02*
X1495268D01*
G01X1491440Y647437D02*
Y650537D01*
X1491900Y649917D01*
G01Y647437D02*
X1490980D01*
G01X1495268Y663185D02*
Y666285D01*
X1493812D01*
G01X1494348Y664787D02*
X1495268D01*
G01X1492283Y663805D02*
X1492053Y663443D01*
X1491747Y663237D01*
X1491402Y663185D01*
X1491095Y663237D01*
X1490788Y663495D01*
X1490597Y663805D01*
X1490558Y664115D01*
X1490635Y664477D01*
X1490903Y664735D01*
X1491172Y664838D01*
X1491517D01*
G01X1491172D02*
X1490942Y664993D01*
X1490750Y665252D01*
X1490673Y665562D01*
X1490750Y665872D01*
X1490942Y666130D01*
X1491287Y666285D01*
X1491632Y666233D01*
X1491977Y666027D01*
G01X1489271Y729449D02*
X1559547D01*
G01X1555050Y78500D02*
G03I-25950J0D01*
G01X1503642Y729449D02*
Y590473D01*
G01X1550100Y599433D02*
X1557600D01*
Y601673D01*
X1557225Y602420D01*
X1556350Y602980D01*
X1555350Y603167D01*
X1554350Y602980D01*
X1553600Y602513D01*
X1553225Y601673D01*
Y599433D01*
G01X1550100Y606933D02*
X1557600D01*
Y609267D01*
X1557225Y610013D01*
X1556725Y610480D01*
X1555725Y610667D01*
X1554725Y610480D01*
X1554100Y609920D01*
X1553725Y609267D01*
Y606933D01*
G01Y609267D02*
X1550100Y610667D01*
G01Y618167D02*
Y614433D01*
X1557600D01*
Y618167D01*
G01X1553975Y616673D02*
Y614433D01*
G01X1551100Y621840D02*
X1550475Y622587D01*
X1550100Y623427D01*
Y624173D01*
X1550475Y624920D01*
X1551100Y625480D01*
X1551975Y625760D01*
X1552850Y625573D01*
X1553600Y625107D01*
X1554100Y624267D01*
X1554350Y623147D01*
X1554850Y622493D01*
X1555725Y622213D01*
X1556600Y622400D01*
X1557225Y622867D01*
X1557600Y623520D01*
Y624173D01*
X1557350Y624827D01*
X1556725Y625387D01*
G01X1551100Y629340D02*
X1550475Y630087D01*
X1550100Y630927D01*
Y631673D01*
X1550475Y632420D01*
X1551100Y632980D01*
X1551975Y633260D01*
X1552850Y633073D01*
X1553600Y632607D01*
X1554100Y631767D01*
X1554350Y630647D01*
X1554850Y629993D01*
X1555725Y629713D01*
X1556600Y629900D01*
X1557225Y630367D01*
X1557600Y631020D01*
Y631673D01*
X1557350Y632327D01*
X1556725Y632887D01*
G01X1552600Y637587D02*
Y640013D01*
G01X1550100Y644527D02*
X1557600D01*
Y648073D01*
G01X1553975Y646767D02*
Y644527D01*
G01X1557600Y652680D02*
Y654920D01*
G01Y653800D02*
X1550100D01*
G01Y652680D02*
Y654920D01*
G01X1557600Y661300D02*
X1550100D01*
G01X1557600Y659153D02*
Y663447D01*
G01X1543308Y738307D02*
X1620079D01*
Y582008D01*
X1543308D01*
Y738307D01*
G01X1559547Y729449D02*
Y590473D01*
G01X1599100Y599933D02*
X1606600D01*
Y602173D01*
X1606225Y602920D01*
X1605350Y603480D01*
X1604350Y603667D01*
X1603350Y603480D01*
X1602600Y603013D01*
X1602225Y602173D01*
Y599933D01*
G01X1599100Y607433D02*
X1606600D01*
Y609767D01*
X1606225Y610513D01*
X1605725Y610980D01*
X1604725Y611167D01*
X1603725Y610980D01*
X1603100Y610420D01*
X1602725Y609767D01*
Y607433D01*
G01Y609767D02*
X1599100Y611167D01*
G01Y618667D02*
Y614933D01*
X1606600D01*
Y618667D01*
G01X1602975Y617173D02*
Y614933D01*
G01X1600100Y622340D02*
X1599475Y623087D01*
X1599100Y623927D01*
Y624673D01*
X1599475Y625420D01*
X1600100Y625980D01*
X1600975Y626260D01*
X1601850Y626073D01*
X1602600Y625607D01*
X1603100Y624767D01*
X1603350Y623647D01*
X1603850Y622993D01*
X1604725Y622713D01*
X1605600Y622900D01*
X1606225Y623367D01*
X1606600Y624020D01*
Y624673D01*
X1606350Y625327D01*
X1605725Y625887D01*
G01X1600100Y629840D02*
X1599475Y630587D01*
X1599100Y631427D01*
Y632173D01*
X1599475Y632920D01*
X1600100Y633480D01*
X1600975Y633760D01*
X1601850Y633573D01*
X1602600Y633107D01*
X1603100Y632267D01*
X1603350Y631147D01*
X1603850Y630493D01*
X1604725Y630213D01*
X1605600Y630400D01*
X1606225Y630867D01*
X1606600Y631520D01*
Y632173D01*
X1606350Y632827D01*
X1605725Y633387D01*
G01X1601600Y638087D02*
Y640513D01*
G01X1599100Y645027D02*
X1606600D01*
Y648573D01*
G01X1602975Y647267D02*
Y645027D01*
G01X1606600Y653180D02*
Y655420D01*
G01Y654300D02*
X1599100D01*
G01Y653180D02*
Y655420D01*
G01X1606600Y661800D02*
X1599100D01*
G01X1606600Y659653D02*
Y663947D01*
G01X1627237Y99334D02*
Y93334D01*
X1639237D01*
Y99334D01*
X1627237D01*
G01X1644943Y141050D02*
Y138828D01*
X1644790Y138363D01*
X1644483Y138053D01*
X1644100Y137950D01*
X1643717Y138053D01*
X1643410Y138363D01*
X1643257Y138828D01*
Y141050D01*
G01X1641843Y138570D02*
X1641613Y138208D01*
X1641307Y138002D01*
X1640962Y137950D01*
X1640655Y138002D01*
X1640348Y138260D01*
X1640157Y138570D01*
X1640118Y138880D01*
X1640195Y139242D01*
X1640463Y139500D01*
X1640732Y139603D01*
X1641077D01*
G01X1640732D02*
X1640502Y139758D01*
X1640310Y140017D01*
X1640233Y140327D01*
X1640310Y140637D01*
X1640502Y140895D01*
X1640847Y141050D01*
X1641192Y140998D01*
X1641537Y140792D01*
G01X1638552Y138312D02*
X1638283Y138053D01*
X1637977Y137950D01*
X1637670Y138053D01*
X1637402Y138363D01*
X1637210Y138828D01*
X1637133Y139293D01*
Y139862D01*
X1637210Y140327D01*
X1637402Y140740D01*
X1637632Y140947D01*
X1637900Y141050D01*
X1638207Y140947D01*
X1638437Y140740D01*
X1638590Y140430D01*
X1638667Y140017D01*
X1638590Y139655D01*
X1638398Y139293D01*
X1638168Y139087D01*
X1637900Y139035D01*
X1637593Y139138D01*
X1637363Y139397D01*
X1637133Y139862D01*
G01X1662900Y143723D02*
Y174923D01*
X1647100D01*
Y143723D01*
X1652700D01*
X1655000Y146023D01*
X1657300Y143723D01*
X1662900D01*
G01X1642677Y125904D02*
Y132104D01*
X1639477D01*
Y125904D01*
X1642677D01*
G01X1625400Y144400D02*
X1631600D01*
Y147600D01*
X1625400D01*
Y144400D01*
G01Y140900D02*
X1631600D01*
Y144100D01*
X1625400D01*
Y140900D01*
G01X1631600Y140600D02*
X1625400D01*
Y137400D01*
X1631600D01*
Y140600D01*
G01X1643677Y132074D02*
Y125874D01*
X1646877D01*
Y132074D01*
X1643677D01*
G01X1625400Y151900D02*
X1631600D01*
Y155100D01*
X1625400D01*
Y151900D01*
G01X1631600Y151100D02*
X1625400D01*
Y147900D01*
X1631600D01*
Y151100D01*
G01X1704724Y236614D02*
G03I-31496J0D01*
G01Y411614D02*
G03I-31496J0D01*
G01X1657100Y139600D02*
X1650900D01*
Y136400D01*
X1657100D01*
Y139600D01*
G01X1682600Y143100D02*
X1676400D01*
Y139900D01*
X1682600D01*
Y143100D01*
G01Y147100D02*
X1676400D01*
Y143900D01*
X1682600D01*
Y147100D01*
G01X1659500Y136400D02*
X1665700D01*
Y139600D01*
X1659500D01*
Y136400D01*
G01X1682600Y155100D02*
X1676400D01*
Y151900D01*
X1682600D01*
Y155100D01*
G01X1676400Y147900D02*
X1682600D01*
Y151100D01*
X1676400D01*
Y147900D01*
G01X1734400Y179400D02*
X1740600D01*
Y182600D01*
X1734400D01*
Y179400D01*
G01Y184900D02*
X1740600D01*
Y188100D01*
X1734400D01*
Y184900D01*
G01X1755543Y179350D02*
Y177128D01*
X1755390Y176663D01*
X1755083Y176353D01*
X1754700Y176250D01*
X1754317Y176353D01*
X1754010Y176663D01*
X1753857Y177128D01*
Y179350D01*
G01X1751140Y176250D02*
Y179350D01*
X1752558Y177128D01*
X1750642D01*
G01X1748500Y179350D02*
X1748807Y179247D01*
X1749037Y178988D01*
X1749190Y178678D01*
X1749305Y178265D01*
X1749343Y177800D01*
X1749305Y177335D01*
X1749190Y176922D01*
X1749037Y176612D01*
X1748807Y176353D01*
X1748500Y176250D01*
X1748193Y176353D01*
X1747963Y176612D01*
X1747810Y176922D01*
X1747695Y177335D01*
X1747657Y177800D01*
X1747695Y178265D01*
X1747810Y178678D01*
X1747963Y178988D01*
X1748193Y179247D01*
X1748500Y179350D01*
G01X1765400Y182400D02*
X1771600D01*
Y185600D01*
X1765400D01*
Y182400D01*
G01X1754100Y184000D02*
X1751498Y181398D01*
X1747276D01*
Y193602D01*
X1760924D01*
Y181398D01*
X1756702D01*
X1754100Y184000D01*
M02*
